FILE_TYPE = MACRO_DRAWING;
SET COLOR_WIRE YELLOW;
SET COLOR_PROP ORANGE;
SET COLOR_DOT WHITE;
SET COLOR_ARC YELLOW;
SET COLOR_BODY GREEN;
SET COLOR_NOTE PURPLE;
SET PROP_DISPLAY VALUE;
SET PAGE_NUMBER P527;
FORCEADD GND_SG..1
(-11900 -50);
FORCEPROP 3 LASTPIN (-11850 0) SIG_NAME SG\g
J 0
(-11840 10);
DISPLAY 0.659574 (-11840 10);
PAINT MONO (-11840 10);
DISPLAY INVISIBLE (-11840 10);
FORCEPROP 1 LAST HDL_POWER SG
J 1
(-11845 -145);
DISPLAY 0.808511 (-11845 -145);
PAINT GREEN (-11845 -145);
FORCEPROP 2 LAST CDS_LIB cls
J 0
(-11900 -50);
DISPLAY INVISIBLE (-11900 -50);
FORCEPROP 1 LAST CDS_LMAN_SYM_OUTLINE 0,0,100,-50
J 0
(-11900 -50);
DISPLAY 0.468085 (-11900 -50);
PAINT GREEN (-11900 -50);
DISPLAY INVISIBLE (-11900 -50);
FORCEPROP 1 LAST BODY_TYPE PLUMBING
J 0
(-11885 -65);
DISPLAY 0.808511 (-11885 -65);
PAINT GREEN (-11885 -65);
DISPLAY INVISIBLE (-11885 -65);
FORCEPROP 1 LAST PATH I1
J 0
(-11865 -50);
DISPLAY 0.808511 (-11865 -50);
PAINT GREEN (-11865 -50);
DISPLAY INVISIBLE (-11865 -50);
FORCEADD GND_SG..1
(-4700 800);
FORCEPROP 3 LASTPIN (-4650 850) SIG_NAME SG\g
J 0
(-4640 860);
DISPLAY 0.659574 (-4640 860);
PAINT MONO (-4640 860);
DISPLAY INVISIBLE (-4640 860);
FORCEPROP 1 LAST HDL_POWER SG
J 1
(-4645 705);
DISPLAY 0.808511 (-4645 705);
PAINT GREEN (-4645 705);
FORCEPROP 2 LAST CDS_LIB cls
J 0
(-4700 800);
DISPLAY INVISIBLE (-4700 800);
FORCEPROP 1 LAST CDS_LMAN_SYM_OUTLINE 0,0,100,-50
J 0
(-4700 800);
DISPLAY 0.468085 (-4700 800);
PAINT GREEN (-4700 800);
DISPLAY INVISIBLE (-4700 800);
FORCEPROP 1 LAST BODY_TYPE PLUMBING
J 0
(-4685 785);
DISPLAY 0.808511 (-4685 785);
PAINT GREEN (-4685 785);
DISPLAY INVISIBLE (-4685 785);
FORCEPROP 1 LAST PATH I100
J 0
(-4665 800);
DISPLAY 0.808511 (-4665 800);
PAINT GREEN (-4665 800);
DISPLAY INVISIBLE (-4665 800);
FORCEADD CAPACITOR..2
R 5
(-4300 950);
FORCEPROP 1 LAST $LOCATION C67
J 0
(-4400 1050);
DISPLAY 1.212766 (-4400 1050);
PAINT GREEN (-4400 1050);
FORCEPROP 0 LAST CDS_LOCATION C67
R 3
J 0
(-4200 850);
DISPLAY 1.021277 (-4200 850);
DISPLAY INVISIBLE (-4200 850);
FORCEPROP 0 LAST $SEC 1
R 3
J 0
(-4200 850);
DISPLAY 0.680851 (-4200 850);
PAINT MONO (-4200 850);
DISPLAY INVISIBLE (-4200 850);
FORCEPROP 0 LAST CDS_SEC 1
R 3
J 0
(-4200 850);
DISPLAY 1.021277 (-4200 850);
DISPLAY INVISIBLE (-4200 850);
FORCEPROP 0 LASTPIN (-4200 950) $PN 1
J 0
(-4190 960);
DISPLAY 0.680851 (-4190 960);
PAINT MONO (-4190 960);
FORCEPROP 0 LASTPIN (-4450 950) $PN 2
J 2
(-4460 960);
DISPLAY 0.680851 (-4460 960);
PAINT MONO (-4460 960);
FORCEPROP 0 LAST VOLTAGE 10V
J 0
(-4400 1150);
DISPLAY 1.021277 (-4400 1150);
FORCEPROP 1 LAST VALUE 0.1UF
J 0
(-4450 800);
DISPLAY 1.212766 (-4450 800);
PAINT GREEN (-4450 800);
FORCEPROP 0 LAST PACKAGE 0402
J 0
(-4400 700);
DISPLAY 1.021277 (-4400 700);
FORCEPROP 0 LAST NO_ASSY TRUE
J 0
(-4550 650);
DISPLAY 1.021277 (-4550 650);
DISPLAY BOTH (-4550 650);
FORCEPROP 2 LAST CDS_LIB passive
R 3
J 0
(-4300 950);
DISPLAY INVISIBLE (-4300 950);
FORCEPROP 1 LAST CDS_LMAN_SYM_OUTLINE -50,0,50,-50
R 3
J 0
(-4300 950);
DISPLAY 0.468085 (-4300 950);
PAINT GREEN (-4300 950);
DISPLAY INVISIBLE (-4300 950);
FORCEPROP 1 LAST CLS_PN G105-0B104-CK
R 3
J 0
(-4250 1050);
DISPLAY 1.212766 (-4250 1050);
PAINT GREEN (-4250 1050);
DISPLAY INVISIBLE (-4250 1050);
FORCEPROP 1 LAST TOLERANCE 10%
R 3
J 0
(-4200 1100);
DISPLAY 1.212766 (-4200 1100);
PAINT GREEN (-4200 1100);
DISPLAY INVISIBLE (-4200 1100);
FORCEPROP 1 LAST PATH I103
R 3
J 0
(-4250 1050);
DISPLAY 1.212766 (-4250 1050);
PAINT GREEN (-4250 1050);
DISPLAY INVISIBLE (-4250 1050);
FORCEADD TS3USB3031RMGR_WQFN12..1
(-3300 950);
FORCEPROP 1 LAST $LOCATION U11
J 0
(-3300 -500);
DISPLAY 1.212766 (-3300 -500);
PAINT GREEN (-3300 -500);
FORCEPROP 0 LAST CDS_LOCATION U11
J 0
(-3300 -200);
DISPLAY 1.021277 (-3300 -200);
DISPLAY INVISIBLE (-3300 -200);
FORCEPROP 0 LAST $SEC 1
J 0
(-3300 -200);
DISPLAY 0.680851 (-3300 -200);
PAINT MONO (-3300 -200);
DISPLAY INVISIBLE (-3300 -200);
FORCEPROP 0 LAST CDS_SEC 1
J 0
(-3300 -200);
DISPLAY 1.021277 (-3300 -200);
DISPLAY INVISIBLE (-3300 -200);
FORCEPROP 0 LASTPIN (-3400 450) $PN 10
J 2
(-3410 460);
DISPLAY 0.680851 (-3410 460);
PAINT MONO (-3410 460);
FORCEPROP 0 LASTPIN (-3400 550) $PN 11
J 2
(-3410 560);
DISPLAY 0.680851 (-3410 560);
PAINT MONO (-3410 560);
FORCEPROP 0 LASTPIN (-2500 -50) $PN 9
J 0
(-2490 -40);
DISPLAY 0.680851 (-2490 -40);
PAINT MONO (-2490 -40);
FORCEPROP 0 LASTPIN (-2500 150) $PN 8
J 0
(-2490 160);
DISPLAY 0.680851 (-2490 160);
PAINT MONO (-2490 160);
FORCEPROP 0 LASTPIN (-2500 250) $PN 7
J 0
(-2490 260);
DISPLAY 0.680851 (-2490 260);
PAINT MONO (-2490 260);
FORCEPROP 0 LASTPIN (-3400 250) $PN 1
J 2
(-3410 260);
DISPLAY 0.680851 (-3410 260);
PAINT MONO (-3410 260);
FORCEPROP 0 LASTPIN (-3400 150) $PN 2
J 2
(-3410 160);
DISPLAY 0.680851 (-3410 160);
PAINT MONO (-3410 160);
FORCEPROP 0 LASTPIN (-2500 750) $PN 4
J 0
(-2490 760);
DISPLAY 0.680851 (-2490 760);
PAINT MONO (-2490 760);
FORCEPROP 0 LASTPIN (-2500 850) $PN 3
J 0
(-2490 860);
DISPLAY 0.680851 (-2490 860);
PAINT MONO (-2490 860);
FORCEPROP 0 LASTPIN (-2500 450) $PN 6
J 0
(-2490 460);
DISPLAY 0.680851 (-2490 460);
PAINT MONO (-2490 460);
FORCEPROP 0 LASTPIN (-2500 550) $PN 5
J 0
(-2490 560);
DISPLAY 0.680851 (-2490 560);
PAINT MONO (-2490 560);
FORCEPROP 0 LASTPIN (-3400 850) $PN 12
J 2
(-3410 860);
DISPLAY 0.680851 (-3410 860);
PAINT MONO (-3410 860);
FORCEPROP 1 LAST VALUE TS3USB3031RMGR
J 0
(-3300 -300);
DISPLAY 1.212766 (-3300 -300);
PAINT GREEN (-3300 -300);
FORCEPROP 0 LAST NO_ASSY TRUE
J 0
(-3050 -500);
DISPLAY 1.021277 (-3050 -500);
DISPLAY BOTH (-3050 -500);
FORCEPROP 1 LAST CLS_PN G220-10368-01
J 0
(-3300 -400);
DISPLAY 1.212766 (-3300 -400);
PAINT GREEN (-3300 -400);
FORCEPROP 2 LAST CDS_LIB stdlogic
J 0
(-3300 950);
DISPLAY INVISIBLE (-3300 950);
FORCEPROP 1 LAST CDS_LMAN_SYM_OUTLINE 0,0,700,-1100
J 0
(-3300 950);
DISPLAY 0.468085 (-3300 950);
PAINT GREEN (-3300 950);
DISPLAY INVISIBLE (-3300 950);
FORCEPROP 1 LAST PATH I108
J 0
(-3250 1000);
DISPLAY 1.212766 (-3250 1000);
PAINT GREEN (-3250 1000);
DISPLAY INVISIBLE (-3250 1000);
FORCEADD OFFPAGE_BI..1
R 6
(-9400 500);
FORCEPROP 2 LAST $XR0 21K12<> 
J 0
(-9340 500);
DISPLAY 0.638298 (-9340 500);
PAINT MONO (-9340 500);
FORCEPROP 1 LAST BODY_TYPE COMMENT
J 0
(-9390 327);
DISPLAY 0.808511 (-9390 327);
PAINT GREEN (-9390 327);
DISPLAY INVISIBLE (-9390 327);
FORCEPROP 1 LAST CDS_LMAN_SYM_OUTLINE -50,50,50,-50
J 0
(-9400 500);
DISPLAY 0.468085 (-9400 500);
PAINT GREEN (-9400 500);
DISPLAY INVISIBLE (-9400 500);
FORCEPROP 2 LAST CDS_LIB cls
J 0
(-9400 500);
DISPLAY INVISIBLE (-9400 500);
FORCEPROP 1 LAST OFFPAGE TRUE
J 0
(-9390 407);
DISPLAY 0.808511 (-9390 407);
PAINT GREEN (-9390 407);
DISPLAY INVISIBLE (-9390 407);
FORCEPROP 2 LAST PATH I11
J 0
(-9300 550);
DISPLAY 1.021277 (-9300 550);
DISPLAY INVISIBLE (-9300 550);
FORCEADD OFFPAGE_BI..1
R 6
(-9400 600);
FORCEPROP 2 LAST $XR0 21K12<> 
J 0
(-9340 600);
DISPLAY 0.638298 (-9340 600);
PAINT MONO (-9340 600);
FORCEPROP 1 LAST BODY_TYPE COMMENT
J 0
(-9390 427);
DISPLAY 0.808511 (-9390 427);
PAINT GREEN (-9390 427);
DISPLAY INVISIBLE (-9390 427);
FORCEPROP 1 LAST CDS_LMAN_SYM_OUTLINE -50,50,50,-50
J 0
(-9400 578);
DISPLAY 0.468085 (-9400 578);
PAINT GREEN (-9400 578);
DISPLAY INVISIBLE (-9400 578);
FORCEPROP 2 LAST CDS_LIB cls
R 2
J 0
(-9400 553);
DISPLAY INVISIBLE (-9400 553);
FORCEPROP 1 LAST OFFPAGE TRUE
J 0
(-9390 507);
DISPLAY 0.808511 (-9390 507);
PAINT GREEN (-9390 507);
DISPLAY INVISIBLE (-9390 507);
FORCEPROP 2 LAST PATH I12
J 0
(-9300 650);
DISPLAY 1.021277 (-9300 650);
DISPLAY INVISIBLE (-9300 650);
FORCEADD OFFPAGE_BI..1
R 4
(-5750 450);
FORCEPROP 2 LAST $XR0 21C13<> 
J 0
(-6000 450);
DISPLAY 0.638298 (-6000 450);
PAINT MONO (-6000 450);
FORCEPROP 2 LAST CDS_LIB cls
R 2
J 0
(-5750 403);
DISPLAY INVISIBLE (-5750 403);
FORCEPROP 1 LAST CDS_LMAN_SYM_OUTLINE -50,50,50,-50
R 2
J 0
(-5750 428);
DISPLAY 0.468085 (-5750 428);
PAINT GREEN (-5750 428);
DISPLAY INVISIBLE (-5750 428);
FORCEPROP 1 LAST BODY_TYPE COMMENT
R 2
J 0
(-5760 239);
DISPLAY 0.808511 (-5760 239);
PAINT GREEN (-5760 239);
DISPLAY INVISIBLE (-5760 239);
FORCEPROP 1 LAST OFFPAGE TRUE
R 2
J 0
(-5760 319);
DISPLAY 0.808511 (-5760 319);
PAINT GREEN (-5760 319);
DISPLAY INVISIBLE (-5760 319);
FORCEPROP 2 LAST PATH I121
R 2
J 0
(-5800 502);
DISPLAY 1.021277 (-5800 502);
DISPLAY INVISIBLE (-5800 502);
FORCEADD OFFPAGE_BI..1
R 4
(-5750 550);
FORCEPROP 2 LAST $XR0 21C13<> 
J 0
(-6000 550);
DISPLAY 0.638298 (-6000 550);
PAINT MONO (-6000 550);
FORCEPROP 2 LAST CDS_LIB cls
R 2
J 0
(-5750 503);
DISPLAY INVISIBLE (-5750 503);
FORCEPROP 1 LAST CDS_LMAN_SYM_OUTLINE -50,50,50,-50
R 2
J 0
(-5750 528);
DISPLAY 0.468085 (-5750 528);
PAINT GREEN (-5750 528);
DISPLAY INVISIBLE (-5750 528);
FORCEPROP 1 LAST BODY_TYPE COMMENT
R 2
J 0
(-5760 339);
DISPLAY 0.808511 (-5760 339);
PAINT GREEN (-5760 339);
DISPLAY INVISIBLE (-5760 339);
FORCEPROP 1 LAST OFFPAGE TRUE
R 2
J 0
(-5760 419);
DISPLAY 0.808511 (-5760 419);
PAINT GREEN (-5760 419);
DISPLAY INVISIBLE (-5760 419);
FORCEPROP 2 LAST PATH I122
R 2
J 0
(-5800 602);
DISPLAY 1.021277 (-5800 602);
DISPLAY INVISIBLE (-5800 602);
FORCEADD RESISTOR..1
(-3000 1200);
FORCEPROP 1 LAST $LOCATION R105
J 2
(-3200 1200);
DISPLAY 1.212766 (-3200 1200);
PAINT GREEN (-3200 1200);
FORCEPROP 0 LAST CDS_LOCATION R105
J 0
(-2750 1300);
DISPLAY 1.021277 (-2750 1300);
DISPLAY INVISIBLE (-2750 1300);
FORCEPROP 0 LAST $SEC 1
J 0
(-2750 1300);
DISPLAY 0.680851 (-2750 1300);
PAINT MONO (-2750 1300);
DISPLAY INVISIBLE (-2750 1300);
FORCEPROP 0 LAST CDS_SEC 1
J 0
(-2750 1300);
DISPLAY 1.021277 (-2750 1300);
DISPLAY INVISIBLE (-2750 1300);
FORCEPROP 0 LASTPIN (-3100 1200) $PN 1
J 2
(-3110 1210);
DISPLAY 0.680851 (-3110 1210);
PAINT MONO (-3110 1210);
FORCEPROP 0 LASTPIN (-2850 1200) $PN 2
J 0
(-2840 1210);
DISPLAY 0.680851 (-2840 1210);
PAINT MONO (-2840 1210);
FORCEPROP 0 LAST PACKAGE 0402
J 0
(-3050 1250);
DISPLAY 1.021277 (-3050 1250);
FORCEPROP 1 LAST VALUE 0OHM
J 0
(-2750 1200);
DISPLAY 1.212766 (-2750 1200);
PAINT GREEN (-2750 1200);
FORCEPROP 1 LAST CDS_LMAN_SYM_OUTLINE -50,50,100,-50
J 0
(-3000 1200);
DISPLAY 0.468085 (-3000 1200);
PAINT GREEN (-3000 1200);
DISPLAY INVISIBLE (-3000 1200);
FORCEPROP 2 LAST CDS_LIB passive
J 0
(-3000 1200);
DISPLAY INVISIBLE (-3000 1200);
FORCEPROP 1 LAST CLS_PN G155-100R0-J0
J 0
(-3136 1400);
DISPLAY 1.212766 (-3136 1400);
PAINT GREEN (-3136 1400);
DISPLAY INVISIBLE (-3136 1400);
FORCEPROP 1 LAST TOLERANCE -
J 0
(-3197 1455);
DISPLAY 1.212766 (-3197 1455);
PAINT GREEN (-3197 1455);
DISPLAY INVISIBLE (-3197 1455);
FORCEPROP 1 LAST PATH I123
J 0
(-3197 1305);
DISPLAY 1.212766 (-3197 1305);
PAINT GREEN (-3197 1305);
DISPLAY INVISIBLE (-3197 1305);
FORCEADD RESISTOR..1
(-3000 1100);
FORCEPROP 1 LAST $LOCATION R106
J 2
(-3200 1100);
DISPLAY 1.212766 (-3200 1100);
PAINT GREEN (-3200 1100);
FORCEPROP 0 LAST CDS_LOCATION R106
J 0
(-2750 1200);
DISPLAY 1.021277 (-2750 1200);
DISPLAY INVISIBLE (-2750 1200);
FORCEPROP 0 LAST $SEC 1
J 0
(-2750 1200);
DISPLAY 0.680851 (-2750 1200);
PAINT MONO (-2750 1200);
DISPLAY INVISIBLE (-2750 1200);
FORCEPROP 0 LAST CDS_SEC 1
J 0
(-2750 1200);
DISPLAY 1.021277 (-2750 1200);
DISPLAY INVISIBLE (-2750 1200);
FORCEPROP 0 LASTPIN (-3100 1100) $PN 1
J 2
(-3110 1110);
DISPLAY 0.680851 (-3110 1110);
PAINT MONO (-3110 1110);
FORCEPROP 0 LASTPIN (-2850 1100) $PN 2
J 0
(-2840 1110);
DISPLAY 0.680851 (-2840 1110);
PAINT MONO (-2840 1110);
FORCEPROP 0 LAST PACKAGE 0402
J 0
(-3050 1000);
DISPLAY 1.021277 (-3050 1000);
FORCEPROP 1 LAST VALUE 0OHM
J 0
(-2750 1100);
DISPLAY 1.212766 (-2750 1100);
PAINT GREEN (-2750 1100);
FORCEPROP 2 LAST CDS_LIB passive
J 0
(-3000 1100);
DISPLAY INVISIBLE (-3000 1100);
FORCEPROP 1 LAST CDS_LMAN_SYM_OUTLINE -50,50,100,-50
J 0
(-3000 1100);
DISPLAY 0.468085 (-3000 1100);
PAINT GREEN (-3000 1100);
DISPLAY INVISIBLE (-3000 1100);
FORCEPROP 1 LAST CLS_PN G155-100R0-J0
J 0
(-3136 1300);
DISPLAY 1.212766 (-3136 1300);
PAINT GREEN (-3136 1300);
DISPLAY INVISIBLE (-3136 1300);
FORCEPROP 1 LAST TOLERANCE -
J 0
(-3197 1355);
DISPLAY 1.212766 (-3197 1355);
PAINT GREEN (-3197 1355);
DISPLAY INVISIBLE (-3197 1355);
FORCEPROP 1 LAST PATH I124
J 0
(-3197 1205);
DISPLAY 1.212766 (-3197 1205);
PAINT GREEN (-3197 1205);
DISPLAY INVISIBLE (-3197 1205);
FORCEADD RESISTOR..2
(-3500 -100);
FORCEPROP 1 LAST $LOCATION R104
J 0
(-3850 -200);
DISPLAY 1.212766 (-3850 -200);
PAINT GREEN (-3850 -200);
FORCEPROP 0 LAST CDS_LOCATION R104
J 0
(-3450 0);
DISPLAY 1.021277 (-3450 0);
DISPLAY INVISIBLE (-3450 0);
FORCEPROP 0 LAST $SEC 1
J 0
(-3450 0);
DISPLAY 0.680851 (-3450 0);
PAINT MONO (-3450 0);
DISPLAY INVISIBLE (-3450 0);
FORCEPROP 0 LAST CDS_SEC 1
J 0
(-3450 0);
DISPLAY 1.021277 (-3450 0);
DISPLAY INVISIBLE (-3450 0);
FORCEPROP 0 LASTPIN (-3500 0) $PN 1
R 1
J 0
(-3510 10);
DISPLAY 0.680851 (-3510 10);
PAINT MONO (-3510 10);
FORCEPROP 0 LASTPIN (-3500 -250) $PN 2
R 1
J 2
(-3510 -260);
DISPLAY 0.680851 (-3510 -260);
PAINT MONO (-3510 -260);
FORCEPROP 0 LAST NO_ASSY TRUE
J 0
(-4200 -350);
DISPLAY 1.021277 (-4200 -350);
DISPLAY BOTH (-4200 -350);
FORCEPROP 0 LAST PACKAGE 0402
J 0
(-3850 -250);
DISPLAY 1.021277 (-3850 -250);
FORCEPROP 1 LAST VALUE 4.7KOHM
J 0
(-3950 -100);
DISPLAY 1.212766 (-3950 -100);
PAINT GREEN (-3950 -100);
FORCEPROP 2 LAST CDS_LIB passive
J 0
(-3500 -100);
DISPLAY INVISIBLE (-3500 -100);
FORCEPROP 1 LAST CDS_LMAN_SYM_OUTLINE -50,50,50,-100
J 0
(-3500 -100);
DISPLAY 0.468085 (-3500 -100);
PAINT GREEN (-3500 -100);
DISPLAY INVISIBLE (-3500 -100);
FORCEPROP 1 LAST CLS_PN G155-14701-01
J 0
(-3636 100);
DISPLAY 1.212766 (-3636 100);
PAINT GREEN (-3636 100);
DISPLAY INVISIBLE (-3636 100);
FORCEPROP 1 LAST TOLERANCE 1%
J 0
(-3697 155);
DISPLAY 1.212766 (-3697 155);
PAINT GREEN (-3697 155);
DISPLAY INVISIBLE (-3697 155);
FORCEPROP 1 LAST PATH I126
J 0
(-3697 5);
DISPLAY 1.212766 (-3697 5);
PAINT GREEN (-3697 5);
DISPLAY INVISIBLE (-3697 5);
FORCEPROP 2 LASTPIN (-3500 0) SIG_NAME UN$527$RESISTOR$I126$1
J 0
(-3490 10);
DISPLAY 0.659574 (-3490 10);
PAINT MONO (-3490 10);
DISPLAY INVISIBLE (-3490 10);
FORCEADD GND_SG..1
(-3550 -400);
FORCEPROP 3 LASTPIN (-3500 -350) SIG_NAME SG\g
J 0
(-3490 -340);
DISPLAY 0.659574 (-3490 -340);
PAINT MONO (-3490 -340);
DISPLAY INVISIBLE (-3490 -340);
FORCEPROP 1 LAST HDL_POWER SG
J 1
(-3495 -495);
DISPLAY 0.808511 (-3495 -495);
PAINT GREEN (-3495 -495);
FORCEPROP 1 LAST CDS_LMAN_SYM_OUTLINE 0,0,100,-50
J 0
(-3550 -400);
DISPLAY 0.468085 (-3550 -400);
PAINT GREEN (-3550 -400);
DISPLAY INVISIBLE (-3550 -400);
FORCEPROP 2 LAST CDS_LIB cls
J 0
(-3550 -400);
DISPLAY INVISIBLE (-3550 -400);
FORCEPROP 1 LAST BODY_TYPE PLUMBING
J 0
(-3535 -415);
DISPLAY 0.808511 (-3535 -415);
PAINT GREEN (-3535 -415);
DISPLAY INVISIBLE (-3535 -415);
FORCEPROP 1 LAST PATH I128
J 0
(-3515 -400);
DISPLAY 0.808511 (-3515 -400);
PAINT GREEN (-3515 -400);
DISPLAY INVISIBLE (-3515 -400);
FORCEADD RESISTOR..1
(-7100 6550);
FORCEPROP 1 LAST $LOCATION R88
J 2
(-7250 6550);
DISPLAY 1.212766 (-7250 6550);
PAINT GREEN (-7250 6550);
FORCEPROP 0 LAST CDS_LOCATION R88
J 0
(-6850 6650);
DISPLAY 1.021277 (-6850 6650);
DISPLAY INVISIBLE (-6850 6650);
FORCEPROP 0 LAST $SEC 1
J 0
(-6850 6650);
DISPLAY 0.680851 (-6850 6650);
PAINT MONO (-6850 6650);
DISPLAY INVISIBLE (-6850 6650);
FORCEPROP 0 LAST CDS_SEC 1
J 0
(-6850 6650);
DISPLAY 1.021277 (-6850 6650);
DISPLAY INVISIBLE (-6850 6650);
FORCEPROP 0 LASTPIN (-7200 6550) $PN 1
J 2
(-7210 6560);
DISPLAY 0.680851 (-7210 6560);
PAINT MONO (-7210 6560);
FORCEPROP 0 LASTPIN (-6950 6550) $PN 2
J 0
(-6940 6560);
DISPLAY 0.680851 (-6940 6560);
PAINT MONO (-6940 6560);
FORCEPROP 0 LAST PACKAGE 0402
J 0
(-7150 6450);
DISPLAY 1.021277 (-7150 6450);
FORCEPROP 1 LAST VALUE 0OHM
J 0
(-6850 6550);
DISPLAY 1.212766 (-6850 6550);
PAINT GREEN (-6850 6550);
FORCEPROP 2 LAST CDS_LIB passive
J 0
(-7100 6550);
DISPLAY INVISIBLE (-7100 6550);
FORCEPROP 1 LAST CDS_LMAN_SYM_OUTLINE -50,50,100,-50
J 0
(-7100 6550);
DISPLAY 0.468085 (-7100 6550);
PAINT GREEN (-7100 6550);
DISPLAY INVISIBLE (-7100 6550);
FORCEPROP 1 LAST CLS_PN G155-100R0-J0
J 0
(-7236 6750);
DISPLAY 1.212766 (-7236 6750);
PAINT GREEN (-7236 6750);
DISPLAY INVISIBLE (-7236 6750);
FORCEPROP 1 LAST TOLERANCE -
J 0
(-7297 6805);
DISPLAY 1.212766 (-7297 6805);
PAINT GREEN (-7297 6805);
DISPLAY INVISIBLE (-7297 6805);
FORCEPROP 1 LAST PATH I13
J 0
(-7297 6655);
DISPLAY 1.212766 (-7297 6655);
PAINT GREEN (-7297 6655);
DISPLAY INVISIBLE (-7297 6655);
FORCEADD OFFPAGE_IN..2
R 2
(-3600 3900);
FORCEPROP 2 LAST $XR0 11F5> 
J 0
(-3783 3900);
DISPLAY 0.638298 (-3783 3900);
PAINT MONO (-3783 3900);
FORCEPROP 1 LAST BODY_TYPE COMMENT
J 2
(-3610 4035);
DISPLAY 0.808511 (-3610 4035);
PAINT GREEN (-3610 4035);
DISPLAY INVISIBLE (-3610 4035);
FORCEPROP 1 LAST CDS_LMAN_SYM_OUTLINE -50,50,50,-50
J 2
(-3600 3900);
DISPLAY 0.468085 (-3600 3900);
PAINT GREEN (-3600 3900);
DISPLAY INVISIBLE (-3600 3900);
FORCEPROP 2 LAST CDS_LIB cls
J 0
(-3600 3900);
DISPLAY INVISIBLE (-3600 3900);
FORCEPROP 1 LAST OFFPAGE TRUE
J 2
(-3610 3955);
DISPLAY 0.808511 (-3610 3955);
PAINT GREEN (-3610 3955);
DISPLAY INVISIBLE (-3610 3955);
FORCEPROP 2 LAST PATH I137
J 0
(-3550 4000);
DISPLAY 1.021277 (-3550 4000);
DISPLAY INVISIBLE (-3550 4000);
FORCEADD GND_SG..1
(-2400 2900);
FORCEPROP 3 LASTPIN (-2350 2950) SIG_NAME SG\g
J 0
(-2340 2960);
DISPLAY 0.659574 (-2340 2960);
PAINT MONO (-2340 2960);
DISPLAY INVISIBLE (-2340 2960);
FORCEPROP 1 LAST HDL_POWER SG
J 1
(-2345 2805);
DISPLAY 0.808511 (-2345 2805);
PAINT GREEN (-2345 2805);
FORCEPROP 1 LAST CDS_LMAN_SYM_OUTLINE 0,0,100,-50
J 0
(-2400 2900);
DISPLAY 0.468085 (-2400 2900);
PAINT GREEN (-2400 2900);
DISPLAY INVISIBLE (-2400 2900);
FORCEPROP 2 LAST CDS_LIB cls
J 0
(-2400 2900);
DISPLAY INVISIBLE (-2400 2900);
FORCEPROP 1 LAST BODY_TYPE PLUMBING
J 0
(-2385 2885);
DISPLAY 0.808511 (-2385 2885);
PAINT GREEN (-2385 2885);
DISPLAY INVISIBLE (-2385 2885);
FORCEPROP 1 LAST PATH I139
J 0
(-2365 2900);
DISPLAY 0.808511 (-2365 2900);
PAINT GREEN (-2365 2900);
DISPLAY INVISIBLE (-2365 2900);
FORCEADD RESISTOR..1
(-7100 6650);
FORCEPROP 1 LAST $LOCATION R87
J 2
(-7250 6650);
DISPLAY 1.212766 (-7250 6650);
PAINT GREEN (-7250 6650);
FORCEPROP 0 LAST CDS_LOCATION R87
J 0
(-6850 6750);
DISPLAY 1.021277 (-6850 6750);
DISPLAY INVISIBLE (-6850 6750);
FORCEPROP 0 LAST $SEC 1
J 0
(-6850 6750);
DISPLAY 0.680851 (-6850 6750);
PAINT MONO (-6850 6750);
DISPLAY INVISIBLE (-6850 6750);
FORCEPROP 0 LAST CDS_SEC 1
J 0
(-6850 6750);
DISPLAY 1.021277 (-6850 6750);
DISPLAY INVISIBLE (-6850 6750);
FORCEPROP 0 LASTPIN (-7200 6650) $PN 1
J 2
(-7210 6660);
DISPLAY 0.680851 (-7210 6660);
PAINT MONO (-7210 6660);
FORCEPROP 0 LASTPIN (-6950 6650) $PN 2
J 0
(-6940 6660);
DISPLAY 0.680851 (-6940 6660);
PAINT MONO (-6940 6660);
FORCEPROP 0 LAST PACKAGE 0402
J 0
(-7150 6700);
DISPLAY 1.021277 (-7150 6700);
FORCEPROP 1 LAST VALUE 0OHM
J 0
(-6850 6650);
DISPLAY 1.212766 (-6850 6650);
PAINT GREEN (-6850 6650);
FORCEPROP 2 LAST CDS_LIB passive
J 0
(-7100 6650);
DISPLAY INVISIBLE (-7100 6650);
FORCEPROP 1 LAST CDS_LMAN_SYM_OUTLINE -50,50,100,-50
J 0
(-7100 6650);
DISPLAY 0.468085 (-7100 6650);
PAINT GREEN (-7100 6650);
DISPLAY INVISIBLE (-7100 6650);
FORCEPROP 1 LAST CLS_PN G155-100R0-J0
J 0
(-7236 6850);
DISPLAY 1.212766 (-7236 6850);
PAINT GREEN (-7236 6850);
DISPLAY INVISIBLE (-7236 6850);
FORCEPROP 1 LAST TOLERANCE -
J 0
(-7297 6905);
DISPLAY 1.212766 (-7297 6905);
PAINT GREEN (-7297 6905);
DISPLAY INVISIBLE (-7297 6905);
FORCEPROP 1 LAST PATH I14
J 0
(-7297 6755);
DISPLAY 1.212766 (-7297 6755);
PAINT GREEN (-7297 6755);
DISPLAY INVISIBLE (-7297 6755);
FORCEADD GND_SG..1
(-1150 2450);
FORCEPROP 3 LASTPIN (-1100 2500) SIG_NAME SG\g
J 0
(-1090 2510);
DISPLAY 0.659574 (-1090 2510);
PAINT MONO (-1090 2510);
DISPLAY INVISIBLE (-1090 2510);
FORCEPROP 1 LAST HDL_POWER SG
J 1
(-1095 2355);
DISPLAY 0.808511 (-1095 2355);
PAINT GREEN (-1095 2355);
FORCEPROP 1 LAST CDS_LMAN_SYM_OUTLINE 0,0,100,-50
J 0
(-1150 2450);
DISPLAY 0.468085 (-1150 2450);
PAINT GREEN (-1150 2450);
DISPLAY INVISIBLE (-1150 2450);
FORCEPROP 2 LAST CDS_LIB cls
J 0
(-1150 2450);
DISPLAY INVISIBLE (-1150 2450);
FORCEPROP 1 LAST BODY_TYPE PLUMBING
J 0
(-1135 2435);
DISPLAY 0.808511 (-1135 2435);
PAINT GREEN (-1135 2435);
DISPLAY INVISIBLE (-1135 2435);
FORCEPROP 1 LAST PATH I143
J 0
(-1115 2450);
DISPLAY 0.808511 (-1115 2450);
PAINT GREEN (-1115 2450);
DISPLAY INVISIBLE (-1115 2450);
FORCEADD CAPACITOR..2
(-1100 3000);
FORCEPROP 1 LAST $LOCATION C68
J 0
(-1050 2850);
DISPLAY 1.212766 (-1050 2850);
PAINT GREEN (-1050 2850);
FORCEPROP 0 LAST CDS_LOCATION C68
J 0
(-1050 3150);
DISPLAY 1.021277 (-1050 3150);
DISPLAY INVISIBLE (-1050 3150);
FORCEPROP 0 LAST $SEC 1
J 0
(-1050 3150);
DISPLAY 0.680851 (-1050 3150);
PAINT MONO (-1050 3150);
DISPLAY INVISIBLE (-1050 3150);
FORCEPROP 0 LAST CDS_SEC 1
J 0
(-1050 3150);
DISPLAY 1.021277 (-1050 3150);
DISPLAY INVISIBLE (-1050 3150);
FORCEPROP 0 LASTPIN (-1100 3100) $PN 1
R 1
J 0
(-1110 3110);
DISPLAY 0.680851 (-1110 3110);
PAINT MONO (-1110 3110);
FORCEPROP 0 LASTPIN (-1100 2850) $PN 2
R 1
J 2
(-1110 2840);
DISPLAY 0.680851 (-1110 2840);
PAINT MONO (-1110 2840);
FORCEPROP 0 LAST PACKAGE 0402
J 0
(-1000 2950);
DISPLAY 1.021277 (-1000 2950);
FORCEPROP 0 LAST VOLTAGE 25V
J 0
(-1050 3200);
DISPLAY 1.021277 (-1050 3200);
FORCEPROP 1 LAST VALUE 0.1UF
J 0
(-1050 3050);
DISPLAY 1.212766 (-1050 3050);
PAINT GREEN (-1050 3050);
FORCEPROP 0 LAST NO_ASSY TRUE
J 0
(-1200 3150);
DISPLAY 1.021277 (-1200 3150);
DISPLAY BOTH (-1200 3150);
FORCEPROP 1 LAST CLS_PN G105-0B104-EK
J 0
(-1200 3050);
DISPLAY 1.212766 (-1200 3050);
PAINT GREEN (-1200 3050);
DISPLAY INVISIBLE (-1200 3050);
FORCEPROP 1 LAST TOLERANCE 10%
J 0
(-1250 3100);
DISPLAY 1.212766 (-1250 3100);
PAINT GREEN (-1250 3100);
DISPLAY INVISIBLE (-1250 3100);
FORCEPROP 1 LAST CDS_LMAN_SYM_OUTLINE -50,0,50,-50
J 0
(-1100 3000);
DISPLAY 0.468085 (-1100 3000);
PAINT GREEN (-1100 3000);
DISPLAY INVISIBLE (-1100 3000);
FORCEPROP 2 LAST CDS_LIB passive
J 0
(-1100 3000);
DISPLAY INVISIBLE (-1100 3000);
FORCEPROP 1 LAST PATH I144
J 0
(-1200 3050);
DISPLAY 1.212766 (-1200 3050);
PAINT GREEN (-1200 3050);
DISPLAY INVISIBLE (-1200 3050);
FORCEADD CL5003148A..2
(-1750 3200);
FORCEPROP 1 LAST $LOCATION U10
J 2
(-1850 2550);
DISPLAY 1.212766 (-1850 2550);
PAINT GREEN (-1850 2550);
FORCEPROP 0 LAST CDS_LOCATION U10
J 0
(-1850 2600);
DISPLAY 1.021277 (-1850 2600);
DISPLAY INVISIBLE (-1850 2600);
FORCEPROP 0 LAST $SEC 2
J 0
(-1850 2600);
DISPLAY 0.680851 (-1850 2600);
PAINT MONO (-1850 2600);
DISPLAY INVISIBLE (-1850 2600);
FORCEPROP 0 LAST CDS_SEC 2
J 0
(-1850 2600);
DISPLAY 1.021277 (-1850 2600);
DISPLAY INVISIBLE (-1850 2600);
FORCEPROP 0 LASTPIN (-1650 2600) $PN 3
R 1
J 2
(-1660 2590);
DISPLAY 0.680851 (-1660 2590);
PAINT MONO (-1660 2590);
FORCEPROP 0 LASTPIN (-1650 3300) $PN 5
R 1
J 0
(-1660 3310);
DISPLAY 0.680851 (-1660 3310);
PAINT MONO (-1660 3310);
FORCEPROP 0 LAST NO_ASSY TRUE
J 0
(-2000 2250);
DISPLAY 1.021277 (-2000 2250);
DISPLAY BOTH (-2000 2250);
FORCEPROP 0 LAST PART_NUMBER SN74LVC1G32DCKR
J 0
(-2000 2350);
DISPLAY 1.021277 (-2000 2350);
FORCEPROP 1 LAST CLS_PN G220-10019-01
J 2
(-1250 2450);
DISPLAY 1.212766 (-1250 2450);
PAINT GREEN (-1250 2450);
FORCEPROP 2 LAST CDS_LIB stdlogic
J 0
(-1750 3200);
DISPLAY INVISIBLE (-1750 3200);
FORCEPROP 1 LAST CDS_LMAN_SYM_OUTLINE 0,0,400,-500
J 0
(-1750 3200);
DISPLAY 0.468085 (-1750 3200);
PAINT GREEN (-1750 3200);
DISPLAY INVISIBLE (-1750 3200);
FORCEPROP 1 LAST PATH I146
J 2
(-1800 3250);
DISPLAY 1.212766 (-1800 3250);
PAINT GREEN (-1800 3250);
DISPLAY INVISIBLE (-1800 3250);
FORCEADD CL5003148A..1
(-2100 4000);
FORCEPROP 1 LAST $LOCATION U10
J 0
(-2100 3500);
DISPLAY 1.212766 (-2100 3500);
PAINT GREEN (-2100 3500);
FORCEPROP 0 LAST CDS_LOCATION U10
J 0
(-2100 3600);
DISPLAY 1.021277 (-2100 3600);
DISPLAY INVISIBLE (-2100 3600);
FORCEPROP 0 LAST $SEC 1
J 0
(-2100 3600);
DISPLAY 0.680851 (-2100 3600);
PAINT MONO (-2100 3600);
DISPLAY INVISIBLE (-2100 3600);
FORCEPROP 0 LAST CDS_SEC 1
J 0
(-2100 3600);
DISPLAY 1.021277 (-2100 3600);
DISPLAY INVISIBLE (-2100 3600);
FORCEPROP 0 LASTPIN (-2200 3900) $PN 1
J 2
(-2210 3910);
DISPLAY 0.680851 (-2210 3910);
PAINT MONO (-2210 3910);
FORCEPROP 0 LASTPIN (-2200 3800) $PN 2
J 2
(-2210 3810);
DISPLAY 0.680851 (-2210 3810);
PAINT MONO (-2210 3810);
FORCEPROP 0 LASTPIN (-1600 3800) $PN 4
J 0
(-1590 3810);
DISPLAY 0.680851 (-1590 3810);
PAINT MONO (-1590 3810);
FORCEPROP 0 LAST NO_ASSY TRUE
J 0
(-1950 3500);
DISPLAY 1.021277 (-1950 3500);
DISPLAY BOTH (-1950 3500);
FORCEPROP 1 LAST CLS_PN G220-10019-01
J 0
(-2100 3400);
DISPLAY 1.212766 (-2100 3400);
PAINT GREEN (-2100 3400);
FORCEPROP 2 LAST CDS_LIB stdlogic
J 0
(-2100 4000);
DISPLAY INVISIBLE (-2100 4000);
FORCEPROP 1 LAST CDS_LMAN_SYM_OUTLINE 0,0,400,-400
J 0
(-2100 4000);
DISPLAY 0.468085 (-2100 4000);
PAINT GREEN (-2100 4000);
DISPLAY INVISIBLE (-2100 4000);
FORCEPROP 1 LAST PATH I147
J 0
(-2082 4259);
DISPLAY 1.212766 (-2082 4259);
PAINT GREEN (-2082 4259);
DISPLAY INVISIBLE (-2082 4259);
FORCEADD RESISTOR..2
(-2350 3400);
FORCEPROP 1 LAST $LOCATION R99
J 0
(-2650 3300);
DISPLAY 1.212766 (-2650 3300);
PAINT GREEN (-2650 3300);
FORCEPROP 0 LAST CDS_LOCATION R99
J 0
(-2800 3500);
DISPLAY 1.021277 (-2800 3500);
DISPLAY INVISIBLE (-2800 3500);
FORCEPROP 0 LAST $SEC 1
J 0
(-2800 3500);
DISPLAY 0.680851 (-2800 3500);
PAINT MONO (-2800 3500);
DISPLAY INVISIBLE (-2800 3500);
FORCEPROP 0 LAST CDS_SEC 1
J 0
(-2800 3500);
DISPLAY 1.021277 (-2800 3500);
DISPLAY INVISIBLE (-2800 3500);
FORCEPROP 0 LASTPIN (-2350 3500) $PN 1
R 1
J 0
(-2360 3510);
DISPLAY 0.680851 (-2360 3510);
PAINT MONO (-2360 3510);
FORCEPROP 0 LASTPIN (-2350 3250) $PN 2
R 1
J 2
(-2360 3240);
DISPLAY 0.680851 (-2360 3240);
PAINT MONO (-2360 3240);
FORCEPROP 0 LAST PACKAGE 0402
J 0
(-2700 3200);
DISPLAY 1.021277 (-2700 3200);
FORCEPROP 1 LAST VALUE 4.7KOHM
J 0
(-2800 3400);
DISPLAY 1.212766 (-2800 3400);
PAINT GREEN (-2800 3400);
FORCEPROP 1 LAST CLS_PN G155-14701-01
J 0
(-2486 3600);
DISPLAY 1.212766 (-2486 3600);
PAINT GREEN (-2486 3600);
DISPLAY INVISIBLE (-2486 3600);
FORCEPROP 2 LAST CDS_LIB passive
J 0
(-2350 3400);
DISPLAY INVISIBLE (-2350 3400);
FORCEPROP 1 LAST CDS_LMAN_SYM_OUTLINE -50,50,50,-100
J 0
(-2350 3400);
DISPLAY 0.468085 (-2350 3400);
PAINT GREEN (-2350 3400);
DISPLAY INVISIBLE (-2350 3400);
FORCEPROP 1 LAST TOLERANCE 1%
J 0
(-2547 3655);
DISPLAY 1.212766 (-2547 3655);
PAINT GREEN (-2547 3655);
DISPLAY INVISIBLE (-2547 3655);
FORCEPROP 1 LAST PATH I149
J 0
(-2547 3505);
DISPLAY 1.212766 (-2547 3505);
PAINT GREEN (-2547 3505);
DISPLAY INVISIBLE (-2547 3505);
FORCEADD CAPACITOR..1
R 3
(-8500 150);
FORCEPROP 1 LAST $LOCATION C63
J 0
(-8400 50);
DISPLAY 1.212766 (-8400 50);
PAINT GREEN (-8400 50);
FORCEPROP 0 LAST CDS_LOCATION C63
R 1
J 0
(-8400 250);
DISPLAY 1.021277 (-8400 250);
DISPLAY INVISIBLE (-8400 250);
FORCEPROP 0 LAST $SEC 1
R 1
J 0
(-8400 250);
DISPLAY 0.680851 (-8400 250);
PAINT MONO (-8400 250);
DISPLAY INVISIBLE (-8400 250);
FORCEPROP 0 LAST CDS_SEC 1
R 1
J 0
(-8400 250);
DISPLAY 1.021277 (-8400 250);
DISPLAY INVISIBLE (-8400 250);
FORCEPROP 0 LASTPIN (-8500 250) $PN 1
R 1
J 0
(-8510 260);
DISPLAY 0.680851 (-8510 260);
PAINT MONO (-8510 260);
FORCEPROP 0 LASTPIN (-8500 0) $PN 2
R 1
J 2
(-8510 -10);
DISPLAY 0.680851 (-8510 -10);
PAINT MONO (-8510 -10);
FORCEPROP 0 LAST VOLTAGE 25V
J 0
(-8400 400);
DISPLAY 1.021277 (-8400 400);
FORCEPROP 1 LAST VALUE 0.1UF
J 0
(-8400 150);
DISPLAY 1.212766 (-8400 150);
PAINT GREEN (-8400 150);
FORCEPROP 0 LAST PACKAGE 0402
J 0
(-8400 300);
DISPLAY 1.021277 (-8400 300);
FORCEPROP 0 LAST NO_ASSY TRUE
J 0
(-8600 450);
DISPLAY 1.021277 (-8600 450);
DISPLAY BOTH (-8600 450);
FORCEPROP 2 LAST CDS_LIB passive
J 0
(-8500 150);
DISPLAY INVISIBLE (-8500 150);
FORCEPROP 1 LAST CDS_LMAN_SYM_OUTLINE 0,50,50,-50
R 1
J 2
(-8500 150);
DISPLAY 0.468085 (-8500 150);
PAINT GREEN (-8500 150);
DISPLAY INVISIBLE (-8500 150);
FORCEPROP 1 LAST TOLERANCE 10%
R 1
J 0
(-8600 250);
DISPLAY 1.212766 (-8600 250);
PAINT GREEN (-8600 250);
DISPLAY INVISIBLE (-8600 250);
FORCEPROP 1 LAST CLS_PN G105-0B104-EK
R 1
J 0
(-8600 200);
DISPLAY 1.212766 (-8600 200);
PAINT GREEN (-8600 200);
DISPLAY INVISIBLE (-8600 200);
FORCEPROP 1 LAST PATH I15
R 1
J 0
(-8600 200);
DISPLAY 1.212766 (-8600 200);
PAINT GREEN (-8600 200);
DISPLAY INVISIBLE (-8600 200);
FORCEADD RESISTOR..1
(-1950 4150);
FORCEPROP 1 LAST $LOCATION R100
J 2
(-2100 4150);
DISPLAY 1.212766 (-2100 4150);
PAINT GREEN (-2100 4150);
FORCEPROP 0 LAST CDS_LOCATION R100
J 0
(-2150 4300);
DISPLAY 1.021277 (-2150 4300);
DISPLAY INVISIBLE (-2150 4300);
FORCEPROP 0 LAST $SEC 1
J 0
(-2150 4300);
DISPLAY 0.680851 (-2150 4300);
PAINT MONO (-2150 4300);
DISPLAY INVISIBLE (-2150 4300);
FORCEPROP 0 LAST CDS_SEC 1
J 0
(-2150 4300);
DISPLAY 1.021277 (-2150 4300);
DISPLAY INVISIBLE (-2150 4300);
FORCEPROP 0 LASTPIN (-2050 4150) $PN 1
J 2
(-2060 4160);
DISPLAY 0.680851 (-2060 4160);
PAINT MONO (-2060 4160);
FORCEPROP 0 LASTPIN (-1800 4150) $PN 2
J 0
(-1790 4160);
DISPLAY 0.680851 (-1790 4160);
PAINT MONO (-1790 4160);
FORCEPROP 0 LAST PACKAGE 0402
J 0
(-2000 4200);
DISPLAY 1.021277 (-2000 4200);
FORCEPROP 1 LAST VALUE 33OHM
J 0
(-1700 4150);
DISPLAY 1.234043 (-1700 4150);
PAINT GREEN (-1700 4150);
FORCEPROP 2 LAST SIGNAL_MODEL DEFAULT_RESISTOR_33OHM_2_1
J 0
(-2100 4350);
DISPLAY 1.021277 (-2100 4350);
DISPLAY INVISIBLE (-2100 4350);
FORCEPROP 1 LAST CDS_LMAN_SYM_OUTLINE -50,50,100,-50
J 0
(-1950 4150);
DISPLAY 0.468085 (-1950 4150);
PAINT GREEN (-1950 4150);
DISPLAY INVISIBLE (-1950 4150);
FORCEPROP 2 LAST CDS_LIB passive
J 0
(-1950 4150);
DISPLAY INVISIBLE (-1950 4150);
FORCEPROP 1 LAST CLS_PN G155-133R0-01
J 0
(-2086 4350);
DISPLAY 1.212766 (-2086 4350);
PAINT GREEN (-2086 4350);
DISPLAY INVISIBLE (-2086 4350);
FORCEPROP 1 LAST TOLERANCE 1%
J 0
(-2147 4405);
DISPLAY 1.212766 (-2147 4405);
PAINT GREEN (-2147 4405);
DISPLAY INVISIBLE (-2147 4405);
FORCEPROP 1 LAST PATH I155
J 0
(-2147 4255);
DISPLAY 1.212766 (-2147 4255);
PAINT GREEN (-2147 4255);
DISPLAY INVISIBLE (-2147 4255);
FORCEADD CAPACITOR..1
R 5
(-8900 150);
FORCEPROP 1 LAST $LOCATION C61
J 2
(-8650 50);
DISPLAY 1.212766 (-8650 50);
PAINT GREEN (-8650 50);
FORCEPROP 0 LAST CDS_LOCATION C61
J 0
(-8800 250);
DISPLAY 1.021277 (-8800 250);
DISPLAY INVISIBLE (-8800 250);
FORCEPROP 0 LAST $SEC 1
J 0
(-8800 250);
DISPLAY 0.680851 (-8800 250);
PAINT MONO (-8800 250);
DISPLAY INVISIBLE (-8800 250);
FORCEPROP 0 LAST CDS_SEC 1
J 0
(-8800 250);
DISPLAY 1.021277 (-8800 250);
DISPLAY INVISIBLE (-8800 250);
FORCEPROP 0 LASTPIN (-8900 250) $PN 1
R 1
J 0
(-8910 260);
DISPLAY 0.680851 (-8910 260);
PAINT MONO (-8910 260);
FORCEPROP 0 LASTPIN (-8900 0) $PN 2
R 1
J 2
(-8910 -10);
DISPLAY 0.680851 (-8910 -10);
PAINT MONO (-8910 -10);
FORCEPROP 0 LAST VOLTAGE 25V
J 0
(-8800 400);
DISPLAY 1.021277 (-8800 400);
FORCEPROP 0 LAST PACKAGE 0805
J 0
(-8800 300);
DISPLAY 1.021277 (-8800 300);
FORCEPROP 1 LAST VALUE 10UF
J 0
(-8800 150);
DISPLAY 1.212766 (-8800 150);
PAINT GREEN (-8800 150);
FORCEPROP 0 LAST NO_ASSY TRUE
J 0
(-9000 500);
DISPLAY 1.021277 (-9000 500);
DISPLAY BOTH (-9000 500);
FORCEPROP 1 LAST TOLERANCE 20%
R 3
J 2
(-8800 250);
DISPLAY 1.212766 (-8800 250);
PAINT GREEN (-8800 250);
DISPLAY INVISIBLE (-8800 250);
FORCEPROP 1 LAST CLS_PN G107-0F106-EM
R 3
J 2
(-8800 200);
DISPLAY 1.212766 (-8800 200);
PAINT GREEN (-8800 200);
DISPLAY INVISIBLE (-8800 200);
FORCEPROP 1 LAST CDS_LMAN_SYM_OUTLINE 0,50,50,-50
R 3
J 0
(-8900 150);
DISPLAY 0.468085 (-8900 150);
PAINT GREEN (-8900 150);
DISPLAY INVISIBLE (-8900 150);
FORCEPROP 2 LAST CDS_LIB passive
J 0
(-8900 150);
DISPLAY INVISIBLE (-8900 150);
FORCEPROP 1 LAST PATH I16
R 3
J 2
(-8800 200);
DISPLAY 1.212766 (-8800 200);
PAINT GREEN (-8800 200);
DISPLAY INVISIBLE (-8800 200);
FORCEADD OFFPAGE_IN..2
R 2
(-3600 3800);
FORCEPROP 2 LAST $XR1 21L8< 
J 0
(-3963 3800);
DISPLAY 0.638298 (-3963 3800);
PAINT MONO (-3963 3800);
FORCEPROP 2 LAST $XR0 21L6> 
J 0
(-3783 3800);
DISPLAY 0.638298 (-3783 3800);
PAINT MONO (-3783 3800);
FORCEPROP 1 LAST BODY_TYPE COMMENT
J 2
(-3610 3935);
DISPLAY 0.808511 (-3610 3935);
PAINT GREEN (-3610 3935);
DISPLAY INVISIBLE (-3610 3935);
FORCEPROP 1 LAST CDS_LMAN_SYM_OUTLINE -50,50,50,-50
J 2
(-3600 3800);
DISPLAY 0.468085 (-3600 3800);
PAINT GREEN (-3600 3800);
DISPLAY INVISIBLE (-3600 3800);
FORCEPROP 2 LAST CDS_LIB cls
J 0
(-3600 3800);
DISPLAY INVISIBLE (-3600 3800);
FORCEPROP 1 LAST OFFPAGE TRUE
J 2
(-3610 3855);
DISPLAY 0.808511 (-3610 3855);
PAINT GREEN (-3610 3855);
DISPLAY INVISIBLE (-3610 3855);
FORCEPROP 2 LAST PATH I161
J 0
(-3550 3900);
DISPLAY 1.021277 (-3550 3900);
DISPLAY INVISIBLE (-3550 3900);
FORCEADD OFFPAGE_BI..1
R 6
(-800 7350);
FORCEPROP 2 LAST $XR0 21K8<> 
J 0
(-740 7350);
DISPLAY 0.638298 (-740 7350);
PAINT MONO (-740 7350);
FORCEPROP 2 LAST CDS_LIB cls
J 0
(-800 7350);
DISPLAY INVISIBLE (-800 7350);
FORCEPROP 1 LAST CDS_LMAN_SYM_OUTLINE -50,50,50,-50
J 0
(-800 7350);
DISPLAY 0.468085 (-800 7350);
PAINT GREEN (-800 7350);
DISPLAY INVISIBLE (-800 7350);
FORCEPROP 1 LAST BODY_TYPE COMMENT
J 0
(-790 7177);
DISPLAY 0.808511 (-790 7177);
PAINT GREEN (-790 7177);
DISPLAY INVISIBLE (-790 7177);
FORCEPROP 1 LAST OFFPAGE TRUE
J 0
(-790 7257);
DISPLAY 0.808511 (-790 7257);
PAINT GREEN (-790 7257);
DISPLAY INVISIBLE (-790 7257);
FORCEPROP 2 LAST PATH I173
J 0
(-750 7450);
DISPLAY 1.021277 (-750 7450);
DISPLAY INVISIBLE (-750 7450);
FORCEADD OFFPAGE_BI..1
R 6
(-800 7450);
FORCEPROP 2 LAST $XR0 21K8<> 
J 0
(-740 7450);
DISPLAY 0.638298 (-740 7450);
PAINT MONO (-740 7450);
FORCEPROP 2 LAST CDS_LIB cls
J 0
(-800 7450);
DISPLAY INVISIBLE (-800 7450);
FORCEPROP 1 LAST CDS_LMAN_SYM_OUTLINE -50,50,50,-50
J 0
(-800 7450);
DISPLAY 0.468085 (-800 7450);
PAINT GREEN (-800 7450);
DISPLAY INVISIBLE (-800 7450);
FORCEPROP 1 LAST BODY_TYPE COMMENT
J 0
(-790 7277);
DISPLAY 0.808511 (-790 7277);
PAINT GREEN (-790 7277);
DISPLAY INVISIBLE (-790 7277);
FORCEPROP 1 LAST OFFPAGE TRUE
J 0
(-790 7357);
DISPLAY 0.808511 (-790 7357);
PAINT GREEN (-790 7357);
DISPLAY INVISIBLE (-790 7357);
FORCEPROP 2 LAST PATH I174
J 0
(-750 7550);
DISPLAY 1.021277 (-750 7550);
DISPLAY INVISIBLE (-750 7550);
FORCEADD RESISTOR..1
(-2700 7350);
FORCEPROP 1 LAST $LOCATION R98
J 2
(-2900 7350);
DISPLAY 1.212766 (-2900 7350);
PAINT GREEN (-2900 7350);
FORCEPROP 0 LAST CDS_LOCATION R98
J 0
(-2450 7450);
DISPLAY 1.021277 (-2450 7450);
DISPLAY INVISIBLE (-2450 7450);
FORCEPROP 0 LAST $SEC 1
J 0
(-2450 7450);
DISPLAY 0.680851 (-2450 7450);
PAINT MONO (-2450 7450);
DISPLAY INVISIBLE (-2450 7450);
FORCEPROP 0 LAST CDS_SEC 1
J 0
(-2450 7450);
DISPLAY 1.021277 (-2450 7450);
DISPLAY INVISIBLE (-2450 7450);
FORCEPROP 0 LASTPIN (-2800 7350) $PN 1
J 2
(-2810 7360);
DISPLAY 0.680851 (-2810 7360);
PAINT MONO (-2810 7360);
FORCEPROP 0 LASTPIN (-2550 7350) $PN 2
J 0
(-2540 7360);
DISPLAY 0.680851 (-2540 7360);
PAINT MONO (-2540 7360);
FORCEPROP 0 LAST PACKAGE 0402
J 0
(-2750 7250);
DISPLAY 1.021277 (-2750 7250);
FORCEPROP 1 LAST VALUE 0OHM
J 0
(-2450 7350);
DISPLAY 1.212766 (-2450 7350);
PAINT GREEN (-2450 7350);
FORCEPROP 2 LAST CDS_LIB passive
J 0
(-2700 7350);
DISPLAY INVISIBLE (-2700 7350);
FORCEPROP 1 LAST CDS_LMAN_SYM_OUTLINE -50,50,100,-50
J 0
(-2700 7350);
DISPLAY 0.468085 (-2700 7350);
PAINT GREEN (-2700 7350);
DISPLAY INVISIBLE (-2700 7350);
FORCEPROP 1 LAST CLS_PN G155-100R0-J0
J 0
(-2836 7550);
DISPLAY 1.212766 (-2836 7550);
PAINT GREEN (-2836 7550);
DISPLAY INVISIBLE (-2836 7550);
FORCEPROP 1 LAST TOLERANCE -
J 0
(-2897 7605);
DISPLAY 1.212766 (-2897 7605);
PAINT GREEN (-2897 7605);
DISPLAY INVISIBLE (-2897 7605);
FORCEPROP 1 LAST PATH I175
J 0
(-2897 7455);
DISPLAY 1.212766 (-2897 7455);
PAINT GREEN (-2897 7455);
DISPLAY INVISIBLE (-2897 7455);
FORCEADD RESISTOR..1
(-2700 7450);
FORCEPROP 1 LAST $LOCATION R97
J 2
(-2900 7450);
DISPLAY 1.212766 (-2900 7450);
PAINT GREEN (-2900 7450);
FORCEPROP 0 LAST CDS_LOCATION R97
J 0
(-2450 7550);
DISPLAY 1.021277 (-2450 7550);
DISPLAY INVISIBLE (-2450 7550);
FORCEPROP 0 LAST $SEC 1
J 0
(-2450 7550);
DISPLAY 0.680851 (-2450 7550);
PAINT MONO (-2450 7550);
DISPLAY INVISIBLE (-2450 7550);
FORCEPROP 0 LAST CDS_SEC 1
J 0
(-2450 7550);
DISPLAY 1.021277 (-2450 7550);
DISPLAY INVISIBLE (-2450 7550);
FORCEPROP 0 LASTPIN (-2800 7450) $PN 1
J 2
(-2810 7460);
DISPLAY 0.680851 (-2810 7460);
PAINT MONO (-2810 7460);
FORCEPROP 0 LASTPIN (-2550 7450) $PN 2
J 0
(-2540 7460);
DISPLAY 0.680851 (-2540 7460);
PAINT MONO (-2540 7460);
FORCEPROP 0 LAST PACKAGE 0402
J 0
(-2750 7500);
DISPLAY 1.021277 (-2750 7500);
FORCEPROP 1 LAST VALUE 0OHM
J 0
(-2450 7450);
DISPLAY 1.212766 (-2450 7450);
PAINT GREEN (-2450 7450);
FORCEPROP 1 LAST CLS_PN G155-100R0-J0
J 0
(-2836 7650);
DISPLAY 1.212766 (-2836 7650);
PAINT GREEN (-2836 7650);
DISPLAY INVISIBLE (-2836 7650);
FORCEPROP 1 LAST CDS_LMAN_SYM_OUTLINE -50,50,100,-50
J 0
(-2700 7450);
DISPLAY 0.468085 (-2700 7450);
PAINT GREEN (-2700 7450);
DISPLAY INVISIBLE (-2700 7450);
FORCEPROP 2 LAST CDS_LIB passive
J 0
(-2700 7450);
DISPLAY INVISIBLE (-2700 7450);
FORCEPROP 1 LAST TOLERANCE -
J 0
(-2897 7705);
DISPLAY 1.212766 (-2897 7705);
PAINT GREEN (-2897 7705);
DISPLAY INVISIBLE (-2897 7705);
FORCEPROP 1 LAST PATH I176
J 0
(-2897 7555);
DISPLAY 1.212766 (-2897 7555);
PAINT GREEN (-2897 7555);
DISPLAY INVISIBLE (-2897 7555);
FORCEADD OFFPAGE_BI..1
R 6
(-1100 450);
FORCEPROP 2 LAST $XR0 21K4<> 
J 0
(-1040 450);
DISPLAY 0.638298 (-1040 450);
PAINT MONO (-1040 450);
FORCEPROP 2 LAST CDS_LIB cls
J 0
(-1100 450);
DISPLAY INVISIBLE (-1100 450);
FORCEPROP 1 LAST CDS_LMAN_SYM_OUTLINE -50,50,50,-50
J 0
(-1100 450);
DISPLAY 0.468085 (-1100 450);
PAINT GREEN (-1100 450);
DISPLAY INVISIBLE (-1100 450);
FORCEPROP 1 LAST BODY_TYPE COMMENT
J 0
(-1090 277);
DISPLAY 0.808511 (-1090 277);
PAINT GREEN (-1090 277);
DISPLAY INVISIBLE (-1090 277);
FORCEPROP 1 LAST OFFPAGE TRUE
J 0
(-1090 357);
DISPLAY 0.808511 (-1090 357);
PAINT GREEN (-1090 357);
DISPLAY INVISIBLE (-1090 357);
FORCEPROP 2 LAST PATH I177
J 0
(-1000 500);
DISPLAY 1.021277 (-1000 500);
DISPLAY INVISIBLE (-1000 500);
FORCEADD OFFPAGE_BI..1
R 6
(-1100 850);
FORCEPROP 2 LAST $XR0 11G12> 
J 0
(-1040 850);
DISPLAY 0.638298 (-1040 850);
PAINT MONO (-1040 850);
FORCEPROP 2 LAST CDS_LIB cls
R 2
J 0
(-1100 803);
DISPLAY INVISIBLE (-1100 803);
FORCEPROP 1 LAST CDS_LMAN_SYM_OUTLINE -50,50,50,-50
J 0
(-1100 828);
DISPLAY 0.468085 (-1100 828);
PAINT GREEN (-1100 828);
DISPLAY INVISIBLE (-1100 828);
FORCEPROP 1 LAST BODY_TYPE COMMENT
J 0
(-1090 677);
DISPLAY 0.808511 (-1090 677);
PAINT GREEN (-1090 677);
DISPLAY INVISIBLE (-1090 677);
FORCEPROP 1 LAST OFFPAGE TRUE
J 0
(-1090 757);
DISPLAY 0.808511 (-1090 757);
PAINT GREEN (-1090 757);
DISPLAY INVISIBLE (-1090 757);
FORCEPROP 2 LAST PATH I178
J 0
(-1000 900);
DISPLAY 1.021277 (-1000 900);
DISPLAY INVISIBLE (-1000 900);
FORCEADD OFFPAGE_BI..1
R 6
(-1100 750);
FORCEPROP 2 LAST $XR0 11G12> 
J 0
(-1040 750);
DISPLAY 0.638298 (-1040 750);
PAINT MONO (-1040 750);
FORCEPROP 1 LAST CDS_LMAN_SYM_OUTLINE -50,50,50,-50
J 0
(-1100 750);
DISPLAY 0.468085 (-1100 750);
PAINT GREEN (-1100 750);
DISPLAY INVISIBLE (-1100 750);
FORCEPROP 2 LAST CDS_LIB cls
J 0
(-1100 750);
DISPLAY INVISIBLE (-1100 750);
FORCEPROP 1 LAST BODY_TYPE COMMENT
J 0
(-1090 577);
DISPLAY 0.808511 (-1090 577);
PAINT GREEN (-1090 577);
DISPLAY INVISIBLE (-1090 577);
FORCEPROP 1 LAST OFFPAGE TRUE
J 0
(-1090 657);
DISPLAY 0.808511 (-1090 657);
PAINT GREEN (-1090 657);
DISPLAY INVISIBLE (-1090 657);
FORCEPROP 2 LAST PATH I179
J 0
(-1000 800);
DISPLAY 1.021277 (-1000 800);
DISPLAY INVISIBLE (-1000 800);
FORCEADD OFFPAGE_BI..1
R 6
(-1100 550);
FORCEPROP 2 LAST $XR0 21K4<> 
J 0
(-1040 550);
DISPLAY 0.638298 (-1040 550);
PAINT MONO (-1040 550);
FORCEPROP 1 LAST CDS_LMAN_SYM_OUTLINE -50,50,50,-50
J 0
(-1100 528);
DISPLAY 0.468085 (-1100 528);
PAINT GREEN (-1100 528);
DISPLAY INVISIBLE (-1100 528);
FORCEPROP 2 LAST CDS_LIB cls
R 2
J 0
(-1100 503);
DISPLAY INVISIBLE (-1100 503);
FORCEPROP 1 LAST BODY_TYPE COMMENT
J 0
(-1090 377);
DISPLAY 0.808511 (-1090 377);
PAINT GREEN (-1090 377);
DISPLAY INVISIBLE (-1090 377);
FORCEPROP 1 LAST OFFPAGE TRUE
J 0
(-1090 457);
DISPLAY 0.808511 (-1090 457);
PAINT GREEN (-1090 457);
DISPLAY INVISIBLE (-1090 457);
FORCEPROP 2 LAST PATH I180
J 0
(-1000 600);
DISPLAY 1.021277 (-1000 600);
DISPLAY INVISIBLE (-1000 600);
FORCEADD RESISTOR..1
(-8050 3800);
FORCEPROP 1 LAST $LOCATION R91
J 2
(-8250 3800);
DISPLAY 1.212766 (-8250 3800);
PAINT GREEN (-8250 3800);
FORCEPROP 0 LAST CDS_LOCATION R91
J 0
(-7850 3900);
DISPLAY 1.021277 (-7850 3900);
DISPLAY INVISIBLE (-7850 3900);
FORCEPROP 0 LAST $SEC 1
J 0
(-7850 3900);
DISPLAY 0.680851 (-7850 3900);
PAINT MONO (-7850 3900);
DISPLAY INVISIBLE (-7850 3900);
FORCEPROP 0 LAST CDS_SEC 1
J 0
(-7850 3900);
DISPLAY 1.021277 (-7850 3900);
DISPLAY INVISIBLE (-7850 3900);
FORCEPROP 0 LASTPIN (-8150 3800) $PN 1
J 2
(-8160 3810);
DISPLAY 0.680851 (-8160 3810);
PAINT MONO (-8160 3810);
FORCEPROP 0 LASTPIN (-7900 3800) $PN 2
J 0
(-7890 3810);
DISPLAY 0.680851 (-7890 3810);
PAINT MONO (-7890 3810);
FORCEPROP 0 LAST NO_ASSY TRUE
J 0
(-8200 3850);
DISPLAY 1.021277 (-8200 3850);
DISPLAY BOTH (-8200 3850);
FORCEPROP 0 LAST PACKAGE 0402
J 0
(-8100 3700);
DISPLAY 1.021277 (-8100 3700);
FORCEPROP 1 LAST VALUE 33OHM
J 0
(-7850 3800);
DISPLAY 1.234043 (-7850 3800);
PAINT GREEN (-7850 3800);
FORCEPROP 2 LAST CDS_LIB passive
J 0
(-8050 3800);
DISPLAY INVISIBLE (-8050 3800);
FORCEPROP 1 LAST CDS_LMAN_SYM_OUTLINE -50,50,100,-50
J 0
(-8050 3800);
DISPLAY 0.468085 (-8050 3800);
PAINT GREEN (-8050 3800);
DISPLAY INVISIBLE (-8050 3800);
FORCEPROP 2 LAST SIGNAL_MODEL DEFAULT_RESISTOR_33OHM_2_1
J 0
(-8200 4000);
DISPLAY 1.021277 (-8200 4000);
DISPLAY INVISIBLE (-8200 4000);
FORCEPROP 1 LAST CLS_PN G155-133R0-01
J 0
(-8186 4000);
DISPLAY 1.212766 (-8186 4000);
PAINT GREEN (-8186 4000);
DISPLAY INVISIBLE (-8186 4000);
FORCEPROP 1 LAST TOLERANCE 1%
J 0
(-8247 4055);
DISPLAY 1.212766 (-8247 4055);
PAINT GREEN (-8247 4055);
DISPLAY INVISIBLE (-8247 4055);
FORCEPROP 1 LAST PATH I187
J 0
(-8247 3905);
DISPLAY 1.212766 (-8247 3905);
PAINT GREEN (-8247 3905);
DISPLAY INVISIBLE (-8247 3905);
FORCEADD VCC..1
(950 4400);
FORCEPROP 3 LASTPIN (1000 4350) SIG_NAME XP3R3V_FPGA\g
J 0
(1010 4360);
DISPLAY 0.659574 (1010 4360);
PAINT MONO (1010 4360);
DISPLAY INVISIBLE (1010 4360);
FORCEPROP 0 LAST VOLTAGE 3.3V
J 0
(700 4550);
DISPLAY 1.021277 (700 4550);
DISPLAY BOTH (700 4550);
FORCEPROP 1 LAST HDL_POWER XP3R3V_FPGA
J 1
(1005 4455);
DISPLAY 1.021277 (1005 4455);
PAINT GREEN (1005 4455);
FORCEPROP 2 LAST CDS_LIB cls
J 0
(950 4400);
DISPLAY INVISIBLE (950 4400);
FORCEPROP 1 LAST CDS_LMAN_SYM_OUTLINE -250,250,250,-250
J 0
(950 4400);
DISPLAY 0.468085 (950 4400);
PAINT GREEN (950 4400);
DISPLAY INVISIBLE (950 4400);
FORCEPROP 1 LAST BODY_TYPE PLUMBING
J 0
(905 4357);
DISPLAY 0.340426 (905 4357);
PAINT GREEN (905 4357);
DISPLAY INVISIBLE (905 4357);
FORCEPROP 1 LAST PATH I190
J 0
(985 4490);
DISPLAY 0.808511 (985 4490);
PAINT GREEN (985 4490);
DISPLAY INVISIBLE (985 4490);
FORCEADD VCC..1
(-1150 3450);
FORCEPROP 3 LASTPIN (-1100 3400) SIG_NAME XP3R3V_FPGA\g
J 0
(-1090 3410);
DISPLAY 0.659574 (-1090 3410);
PAINT MONO (-1090 3410);
DISPLAY INVISIBLE (-1090 3410);
FORCEPROP 1 LAST HDL_POWER XP3R3V_FPGA
J 1
(-1095 3505);
DISPLAY 1.021277 (-1095 3505);
PAINT GREEN (-1095 3505);
FORCEPROP 0 LAST VOLTAGE 3.3V
J 0
(-1400 3600);
DISPLAY 1.021277 (-1400 3600);
DISPLAY BOTH (-1400 3600);
FORCEPROP 2 LAST CDS_LIB cls
J 0
(-1150 3450);
DISPLAY INVISIBLE (-1150 3450);
FORCEPROP 1 LAST CDS_LMAN_SYM_OUTLINE -250,250,250,-250
J 0
(-1150 3450);
DISPLAY 0.468085 (-1150 3450);
PAINT GREEN (-1150 3450);
DISPLAY INVISIBLE (-1150 3450);
FORCEPROP 1 LAST BODY_TYPE PLUMBING
J 0
(-1195 3407);
DISPLAY 0.340426 (-1195 3407);
PAINT GREEN (-1195 3407);
DISPLAY INVISIBLE (-1195 3407);
FORCEPROP 1 LAST PATH I191
J 0
(-1115 3540);
DISPLAY 0.808511 (-1115 3540);
PAINT GREEN (-1115 3540);
DISPLAY INVISIBLE (-1115 3540);
FORCEADD VCC..1
(-4050 1150);
FORCEPROP 3 LASTPIN (-4000 1100) SIG_NAME XP3R3V_FPGA\g
J 0
(-3990 1110);
DISPLAY 0.659574 (-3990 1110);
PAINT MONO (-3990 1110);
DISPLAY INVISIBLE (-3990 1110);
FORCEPROP 0 LAST VOLTAGE 3.3V
J 0
(-4300 1300);
DISPLAY 1.021277 (-4300 1300);
DISPLAY BOTH (-4300 1300);
FORCEPROP 1 LAST HDL_POWER XP3R3V_FPGA
J 1
(-3995 1205);
DISPLAY 1.021277 (-3995 1205);
PAINT GREEN (-3995 1205);
FORCEPROP 2 LAST CDS_LIB cls
J 0
(-4050 1150);
DISPLAY INVISIBLE (-4050 1150);
FORCEPROP 1 LAST CDS_LMAN_SYM_OUTLINE -250,250,250,-250
J 0
(-4050 1150);
DISPLAY 0.468085 (-4050 1150);
PAINT GREEN (-4050 1150);
DISPLAY INVISIBLE (-4050 1150);
FORCEPROP 1 LAST BODY_TYPE PLUMBING
J 0
(-4095 1107);
DISPLAY 0.340426 (-4095 1107);
PAINT GREEN (-4095 1107);
DISPLAY INVISIBLE (-4095 1107);
FORCEPROP 1 LAST PATH I192
J 0
(-4015 1240);
DISPLAY 0.808511 (-4015 1240);
PAINT GREEN (-4015 1240);
DISPLAY INVISIBLE (-4015 1240);
FORCEADD CONN_HDR_2X10_M_S_SMT..1
(-5150 7550);
FORCEPROP 1 LAST $LOCATION P1
J 0
(-5150 7800);
DISPLAY 1.212766 (-5150 7800);
PAINT GREEN (-5150 7800);
FORCEPROP 0 LAST CDS_LOCATION P1
J 0
(-5150 7800);
DISPLAY 1.212766 (-5150 7800);
PAINT GREEN (-5150 7800);
DISPLAY INVISIBLE (-5150 7800);
FORCEPROP 0 LAST $SEC 1
J 0
(-5150 7900);
DISPLAY 0.680851 (-5150 7900);
PAINT MONO (-5150 7900);
DISPLAY INVISIBLE (-5150 7900);
FORCEPROP 0 LAST CDS_SEC 1
J 0
(-5150 7900);
DISPLAY 1.021277 (-5150 7900);
DISPLAY INVISIBLE (-5150 7900);
FORCEPROP 0 LASTPIN (-5250 7450) $PN 1
J 2
(-5260 7460);
DISPLAY 0.680851 (-5260 7460);
PAINT MONO (-5260 7460);
FORCEPROP 0 LASTPIN (-4550 7450) $PN 2
J 0
(-4540 7460);
DISPLAY 0.680851 (-4540 7460);
PAINT MONO (-4540 7460);
FORCEPROP 0 LASTPIN (-5250 7350) $PN 3
J 2
(-5260 7360);
DISPLAY 0.680851 (-5260 7360);
PAINT MONO (-5260 7360);
FORCEPROP 0 LASTPIN (-4550 7350) $PN 4
J 0
(-4540 7360);
DISPLAY 0.680851 (-4540 7360);
PAINT MONO (-4540 7360);
FORCEPROP 0 LASTPIN (-5250 7250) $PN 5
J 2
(-5260 7260);
DISPLAY 0.680851 (-5260 7260);
PAINT MONO (-5260 7260);
FORCEPROP 0 LASTPIN (-4550 7250) $PN 6
J 0
(-4540 7260);
DISPLAY 0.680851 (-4540 7260);
PAINT MONO (-4540 7260);
FORCEPROP 0 LASTPIN (-5250 7150) $PN 7
J 2
(-5260 7160);
DISPLAY 0.680851 (-5260 7160);
PAINT MONO (-5260 7160);
FORCEPROP 0 LASTPIN (-4550 7150) $PN 8
J 0
(-4540 7160);
DISPLAY 0.680851 (-4540 7160);
PAINT MONO (-4540 7160);
FORCEPROP 0 LASTPIN (-5250 7050) $PN 9
J 2
(-5260 7060);
DISPLAY 0.680851 (-5260 7060);
PAINT MONO (-5260 7060);
FORCEPROP 0 LASTPIN (-4550 7050) $PN 10
J 0
(-4540 7060);
DISPLAY 0.680851 (-4540 7060);
PAINT MONO (-4540 7060);
FORCEPROP 0 LASTPIN (-5250 6950) $PN 11
J 2
(-5260 6960);
DISPLAY 0.680851 (-5260 6960);
PAINT MONO (-5260 6960);
FORCEPROP 0 LASTPIN (-4550 6950) $PN 12
J 0
(-4540 6960);
DISPLAY 0.680851 (-4540 6960);
PAINT MONO (-4540 6960);
FORCEPROP 0 LASTPIN (-5250 6850) $PN 13
J 2
(-5260 6860);
DISPLAY 0.680851 (-5260 6860);
PAINT MONO (-5260 6860);
FORCEPROP 0 LASTPIN (-4550 6850) $PN 14
J 0
(-4540 6860);
DISPLAY 0.680851 (-4540 6860);
PAINT MONO (-4540 6860);
FORCEPROP 0 LASTPIN (-5250 6750) $PN 15
J 2
(-5260 6760);
DISPLAY 0.680851 (-5260 6760);
PAINT MONO (-5260 6760);
FORCEPROP 0 LASTPIN (-4550 6750) $PN 16
J 0
(-4540 6760);
DISPLAY 0.680851 (-4540 6760);
PAINT MONO (-4540 6760);
FORCEPROP 0 LASTPIN (-5250 6650) $PN 17
J 2
(-5260 6660);
DISPLAY 0.680851 (-5260 6660);
PAINT MONO (-5260 6660);
FORCEPROP 0 LASTPIN (-4550 6650) $PN 18
J 0
(-4540 6660);
DISPLAY 0.680851 (-4540 6660);
PAINT MONO (-4540 6660);
FORCEPROP 0 LASTPIN (-5250 6550) $PN 19
J 2
(-5260 6560);
DISPLAY 0.680851 (-5260 6560);
PAINT MONO (-5260 6560);
FORCEPROP 0 LASTPIN (-4550 6550) $PN 20
J 0
(-4540 6560);
DISPLAY 0.680851 (-4540 6560);
PAINT MONO (-4540 6560);
FORCEPROP 1 LAST CLS_PN G200-13077-01
J 0
(-5150 7600);
DISPLAY 1.212766 (-5150 7600);
PAINT GREEN (-5150 7600);
FORCEPROP 0 LAST VALUE 52991-0208
J 0
(-5150 7700);
FORCEPROP 2 LAST CDS_LIB connector
J 0
(-5150 7550);
DISPLAY INVISIBLE (-5150 7550);
FORCEPROP 1 LAST CDS_LMAN_SYM_OUTLINE 0,0,500,-1050
J 0
(-5150 7550);
DISPLAY 0.468085 (-5150 7550);
PAINT GREEN (-5150 7550);
DISPLAY INVISIBLE (-5150 7550);
FORCEPROP 1 LAST PATH I193
J 0
(-5100 7600);
DISPLAY 1.212766 (-5100 7600);
PAINT GREEN (-5100 7600);
DISPLAY INVISIBLE (-5100 7600);
FORCEADD CONN_HDR_1X3_M_S_SMT..1
(-5600 4000);
FORCEPROP 1 LAST $LOCATION J18
J 0
(-5600 4050);
DISPLAY 1.212766 (-5600 4050);
PAINT GREEN (-5600 4050);
FORCEPROP 0 LAST CDS_LOCATION J18
J 0
(-5550 4300);
DISPLAY 1.021277 (-5550 4300);
DISPLAY INVISIBLE (-5550 4300);
FORCEPROP 0 LAST $SEC 1
J 0
(-5550 4300);
DISPLAY 0.680851 (-5550 4300);
PAINT MONO (-5550 4300);
DISPLAY INVISIBLE (-5550 4300);
FORCEPROP 0 LAST CDS_SEC 1
J 0
(-5550 4300);
DISPLAY 1.021277 (-5550 4300);
DISPLAY INVISIBLE (-5550 4300);
FORCEPROP 0 LASTPIN (-5200 3900) $PN 1
J 0
(-5190 3910);
DISPLAY 0.680851 (-5190 3910);
PAINT MONO (-5190 3910);
FORCEPROP 0 LASTPIN (-5700 3800) $PN 2
J 2
(-5710 3810);
DISPLAY 0.680851 (-5710 3810);
PAINT MONO (-5710 3810);
FORCEPROP 0 LASTPIN (-5200 3700) $PN 3
J 0
(-5190 3710);
DISPLAY 0.680851 (-5190 3710);
PAINT MONO (-5190 3710);
FORCEPROP 0 LAST NO_ASSY TRUE
J 0
(-5550 4250);
DISPLAY 1.021277 (-5550 4250);
DISPLAY BOTH (-5550 4250);
FORCEPROP 1 LAST CLS_PN G205-10020-01
J 0
(-5600 4150);
DISPLAY 1.212766 (-5600 4150);
PAINT GREEN (-5600 4150);
FORCEPROP 1 LAST CDS_LMAN_SYM_OUTLINE 0,0,300,-400
J 0
(-5600 4000);
DISPLAY 0.468085 (-5600 4000);
PAINT GREEN (-5600 4000);
DISPLAY INVISIBLE (-5600 4000);
FORCEPROP 2 LAST CDS_LIB connector
J 0
(-5600 4000);
DISPLAY INVISIBLE (-5600 4000);
FORCEPROP 1 LAST PATH I198
J 0
(-5550 4050);
DISPLAY 1.212766 (-5550 4050);
PAINT GREEN (-5550 4050);
DISPLAY INVISIBLE (-5550 4050);
FORCEADD GND_SG..1
(-5100 3550);
FORCEPROP 3 LASTPIN (-5050 3600) SIG_NAME SG\g
J 0
(-5040 3610);
DISPLAY 0.659574 (-5040 3610);
PAINT MONO (-5040 3610);
DISPLAY INVISIBLE (-5040 3610);
FORCEPROP 1 LAST HDL_POWER SG
J 1
(-5050 3450);
DISPLAY 0.808511 (-5050 3450);
PAINT GREEN (-5050 3450);
FORCEPROP 2 LAST CDS_LIB cls
J 0
(-5100 3550);
DISPLAY INVISIBLE (-5100 3550);
FORCEPROP 1 LAST CDS_LMAN_SYM_OUTLINE 0,0,100,-50
J 0
(-5100 3550);
DISPLAY 0.468085 (-5100 3550);
PAINT GREEN (-5100 3550);
DISPLAY INVISIBLE (-5100 3550);
FORCEPROP 1 LAST BODY_TYPE PLUMBING
J 0
(-5085 3535);
DISPLAY 0.808511 (-5085 3535);
PAINT GREEN (-5085 3535);
DISPLAY INVISIBLE (-5085 3535);
FORCEPROP 1 LAST PATH I199
J 0
(-5065 3550);
DISPLAY 0.808511 (-5065 3550);
PAINT GREEN (-5065 3550);
DISPLAY INVISIBLE (-5065 3550);
FORCEADD CONN_USB_1X5_G2_GH4_F_RA_SMT..1
R 2
(-11200 800);
FORCEPROP 1 LAST $LOCATION J11
J 2
(-11150 -150);
DISPLAY 1.212766 (-11150 -150);
PAINT GREEN (-11150 -150);
FORCEPROP 0 LAST CDS_LOCATION J11
J 0
(-11150 1150);
DISPLAY 1.021277 (-11150 1150);
DISPLAY INVISIBLE (-11150 1150);
FORCEPROP 0 LAST $SEC 1
J 0
(-11150 1150);
DISPLAY 0.680851 (-11150 1150);
PAINT MONO (-11150 1150);
DISPLAY INVISIBLE (-11150 1150);
FORCEPROP 0 LAST CDS_SEC 1
J 0
(-11150 1150);
DISPLAY 1.021277 (-11150 1150);
DISPLAY INVISIBLE (-11150 1150);
FORCEPROP 0 LASTPIN (-11100 700) $PN 1
J 0
(-11090 710);
DISPLAY 0.680851 (-11090 710);
PAINT MONO (-11090 710);
FORCEPROP 0 LASTPIN (-11100 600) $PN 2
J 0
(-11090 610);
DISPLAY 0.680851 (-11090 610);
PAINT MONO (-11090 610);
FORCEPROP 0 LASTPIN (-11100 500) $PN 3
J 0
(-11090 510);
DISPLAY 0.680851 (-11090 510);
PAINT MONO (-11090 510);
FORCEPROP 0 LASTPIN (-11100 400) $PN 4
J 0
(-11090 410);
DISPLAY 0.680851 (-11090 410);
PAINT MONO (-11090 410);
FORCEPROP 0 LASTPIN (-11100 300) $PN 5
J 0
(-11090 310);
DISPLAY 0.680851 (-11090 310);
PAINT MONO (-11090 310);
FORCEPROP 0 LASTPIN (-11700 700) $PN G1
J 2
(-11710 710);
DISPLAY 0.680851 (-11710 710);
PAINT MONO (-11710 710);
FORCEPROP 0 LASTPIN (-11700 600) $PN G2
J 2
(-11710 610);
DISPLAY 0.680851 (-11710 610);
PAINT MONO (-11710 610);
FORCEPROP 0 LASTPIN (-11700 400) $PN GH1
J 2
(-11710 410);
DISPLAY 0.680851 (-11710 410);
PAINT MONO (-11710 410);
FORCEPROP 0 LASTPIN (-11700 300) $PN GH2
J 2
(-11710 310);
DISPLAY 0.680851 (-11710 310);
PAINT MONO (-11710 310);
FORCEPROP 0 LASTPIN (-11700 200) $PN GH3
J 2
(-11710 210);
DISPLAY 0.680851 (-11710 210);
PAINT MONO (-11710 210);
FORCEPROP 0 LASTPIN (-11700 100) $PN GH4
J 2
(-11710 110);
DISPLAY 0.680851 (-11710 110);
PAINT MONO (-11710 110);
FORCEPROP 1 LAST VALUE 1050171001
J 2
(-11150 -250);
DISPLAY 1.212766 (-11150 -250);
PAINT GREEN (-11150 -250);
FORCEPROP 1 LAST CLS_PN G200-12192-01
J 2
(-11150 -350);
DISPLAY 1.212766 (-11150 -350);
PAINT GREEN (-11150 -350);
FORCEPROP 0 LAST NO_ASSY TRUE
J 0
(-11650 850);
DISPLAY 1.021277 (-11650 850);
DISPLAY BOTH (-11650 850);
FORCEPROP 1 LAST CDS_LMAN_SYM_OUTLINE 0,0,400,-800
J 2
(-11200 800);
DISPLAY 0.468085 (-11200 800);
PAINT GREEN (-11200 800);
DISPLAY INVISIBLE (-11200 800);
FORCEPROP 2 LAST CDS_LIB connector
J 0
(-11200 800);
DISPLAY INVISIBLE (-11200 800);
FORCEPROP 1 LAST PATH I2
J 2
(-11250 850);
DISPLAY 1.212766 (-11250 850);
PAINT GREEN (-11250 850);
DISPLAY INVISIBLE (-11250 850);
FORCEADD RESISTOR..2
(-8050 500);
FORCEPROP 1 LAST $LOCATION R101
J 0
(-8000 400);
DISPLAY 1.212766 (-8000 400);
PAINT GREEN (-8000 400);
FORCEPROP 0 LAST CDS_LOCATION R101
J 0
(-8500 600);
DISPLAY 1.021277 (-8500 600);
DISPLAY INVISIBLE (-8500 600);
FORCEPROP 0 LAST $SEC 1
J 0
(-8500 600);
DISPLAY 0.680851 (-8500 600);
PAINT MONO (-8500 600);
DISPLAY INVISIBLE (-8500 600);
FORCEPROP 0 LAST CDS_SEC 1
J 0
(-8500 600);
DISPLAY 1.021277 (-8500 600);
DISPLAY INVISIBLE (-8500 600);
FORCEPROP 0 LASTPIN (-8050 600) $PN 1
R 1
J 0
(-8060 610);
DISPLAY 0.680851 (-8060 610);
PAINT MONO (-8060 610);
FORCEPROP 0 LASTPIN (-8050 350) $PN 2
R 1
J 2
(-8060 340);
DISPLAY 0.680851 (-8060 340);
PAINT MONO (-8060 340);
FORCEPROP 0 LAST PACKAGE 0402
J 0
(-8000 600);
DISPLAY 1.021277 (-8000 600);
FORCEPROP 1 LAST VALUE 1KOHM
J 0
(-8000 500);
DISPLAY 1.212766 (-8000 500);
PAINT GREEN (-8000 500);
FORCEPROP 0 LAST NO_ASSY TRUE
J 0
(-7750 550);
DISPLAY 1.021277 (-7750 550);
DISPLAY BOTH (-7750 550);
FORCEPROP 2 LAST CDS_LIB passive
J 0
(-8050 500);
DISPLAY INVISIBLE (-8050 500);
FORCEPROP 1 LAST CDS_LMAN_SYM_OUTLINE -50,50,50,-100
J 0
(-8050 500);
DISPLAY 0.468085 (-8050 500);
PAINT GREEN (-8050 500);
DISPLAY INVISIBLE (-8050 500);
FORCEPROP 1 LAST CLS_PN G155-11001-01
J 0
(-8186 700);
DISPLAY 1.212766 (-8186 700);
PAINT GREEN (-8186 700);
DISPLAY INVISIBLE (-8186 700);
FORCEPROP 1 LAST TOLERANCE 1%
J 0
(-8247 755);
DISPLAY 1.212766 (-8247 755);
PAINT GREEN (-8247 755);
DISPLAY INVISIBLE (-8247 755);
FORCEPROP 1 LAST PATH I200
J 0
(-8247 605);
DISPLAY 1.212766 (-8247 605);
PAINT GREEN (-8247 605);
DISPLAY INVISIBLE (-8247 605);
FORCEADD RESISTOR..2
(-8050 50);
FORCEPROP 1 LAST $LOCATION R102
J 0
(-8000 -50);
DISPLAY 1.212766 (-8000 -50);
PAINT GREEN (-8000 -50);
FORCEPROP 0 LAST CDS_LOCATION R102
J 0
(-8500 150);
DISPLAY 1.021277 (-8500 150);
DISPLAY INVISIBLE (-8500 150);
FORCEPROP 0 LAST $SEC 1
J 0
(-8500 150);
DISPLAY 0.680851 (-8500 150);
PAINT MONO (-8500 150);
DISPLAY INVISIBLE (-8500 150);
FORCEPROP 0 LAST CDS_SEC 1
J 0
(-8500 150);
DISPLAY 1.021277 (-8500 150);
DISPLAY INVISIBLE (-8500 150);
FORCEPROP 0 LASTPIN (-8050 150) $PN 1
R 1
J 0
(-8060 160);
DISPLAY 0.680851 (-8060 160);
PAINT MONO (-8060 160);
FORCEPROP 0 LASTPIN (-8050 -100) $PN 2
R 1
J 2
(-8060 -110);
DISPLAY 0.680851 (-8060 -110);
PAINT MONO (-8060 -110);
FORCEPROP 0 LAST PACKAGE 0402
J 0
(-8000 150);
DISPLAY 1.021277 (-8000 150);
FORCEPROP 1 LAST VALUE 1KOHM
J 0
(-8000 50);
DISPLAY 1.212766 (-8000 50);
PAINT GREEN (-8000 50);
FORCEPROP 0 LAST NO_ASSY TRUE
J 0
(-7800 0);
DISPLAY 1.021277 (-7800 0);
DISPLAY BOTH (-7800 0);
FORCEPROP 1 LAST CDS_LMAN_SYM_OUTLINE -50,50,50,-100
J 0
(-8050 50);
DISPLAY 0.468085 (-8050 50);
PAINT GREEN (-8050 50);
DISPLAY INVISIBLE (-8050 50);
FORCEPROP 2 LAST CDS_LIB passive
J 0
(-8050 50);
DISPLAY INVISIBLE (-8050 50);
FORCEPROP 1 LAST CLS_PN G155-11001-01
J 0
(-8186 250);
DISPLAY 1.212766 (-8186 250);
PAINT GREEN (-8186 250);
DISPLAY INVISIBLE (-8186 250);
FORCEPROP 1 LAST TOLERANCE 1%
J 0
(-8247 305);
DISPLAY 1.212766 (-8247 305);
PAINT GREEN (-8247 305);
DISPLAY INVISIBLE (-8247 305);
FORCEPROP 1 LAST PATH I201
J 0
(-8247 155);
DISPLAY 1.212766 (-8247 155);
PAINT GREEN (-8247 155);
DISPLAY INVISIBLE (-8247 155);
FORCEPROP 2 LASTPIN (-8050 -100) SIG_NAME UN$527$RESISTOR$I201$2
J 0
(-8040 -90);
DISPLAY 0.659574 (-8040 -90);
PAINT MONO (-8040 -90);
DISPLAY INVISIBLE (-8040 -90);
FORCEADD RESISTOR..2
(-8050 -300);
FORCEPROP 1 LAST $LOCATION R103
J 0
(-8000 -400);
DISPLAY 1.212766 (-8000 -400);
PAINT GREEN (-8000 -400);
FORCEPROP 0 LAST CDS_LOCATION R103
J 0
(-8500 -150);
DISPLAY 1.021277 (-8500 -150);
DISPLAY INVISIBLE (-8500 -150);
FORCEPROP 0 LAST $SEC 1
J 0
(-8500 -150);
DISPLAY 0.680851 (-8500 -150);
PAINT MONO (-8500 -150);
DISPLAY INVISIBLE (-8500 -150);
FORCEPROP 0 LAST CDS_SEC 1
J 0
(-8500 -150);
DISPLAY 1.021277 (-8500 -150);
DISPLAY INVISIBLE (-8500 -150);
FORCEPROP 0 LASTPIN (-8050 -200) $PN 1
R 1
J 0
(-8060 -190);
DISPLAY 0.680851 (-8060 -190);
PAINT MONO (-8060 -190);
FORCEPROP 0 LASTPIN (-8050 -450) $PN 2
R 1
J 2
(-8060 -460);
DISPLAY 0.680851 (-8060 -460);
PAINT MONO (-8060 -460);
FORCEPROP 0 LAST NO_ASSY TRUE
J 0
(-7750 -400);
DISPLAY 1.021277 (-7750 -400);
DISPLAY BOTH (-7750 -400);
FORCEPROP 0 LAST PACKAGE 0402
J 0
(-8000 -200);
DISPLAY 1.021277 (-8000 -200);
FORCEPROP 1 LAST VALUE 1KOHM
J 0
(-8000 -300);
DISPLAY 1.212766 (-8000 -300);
PAINT GREEN (-8000 -300);
FORCEPROP 1 LAST CDS_LMAN_SYM_OUTLINE -50,50,50,-100
J 0
(-8050 -300);
DISPLAY 0.468085 (-8050 -300);
PAINT GREEN (-8050 -300);
DISPLAY INVISIBLE (-8050 -300);
FORCEPROP 2 LAST CDS_LIB passive
J 0
(-8050 -300);
DISPLAY INVISIBLE (-8050 -300);
FORCEPROP 1 LAST CLS_PN G155-11001-01
J 0
(-8186 -100);
DISPLAY 1.212766 (-8186 -100);
PAINT GREEN (-8186 -100);
DISPLAY INVISIBLE (-8186 -100);
FORCEPROP 1 LAST TOLERANCE 1%
J 0
(-8247 -45);
DISPLAY 1.212766 (-8247 -45);
PAINT GREEN (-8247 -45);
DISPLAY INVISIBLE (-8247 -45);
FORCEPROP 1 LAST PATH I202
J 0
(-8247 -195);
DISPLAY 1.212766 (-8247 -195);
PAINT GREEN (-8247 -195);
DISPLAY INVISIBLE (-8247 -195);
FORCEADD OFFPAGE_OUT..1
(-6900 250);
FORCEPROP 2 LAST $XR1 21L8< 
J 0
(-6635 250);
DISPLAY 0.638298 (-6635 250);
PAINT MONO (-6635 250);
FORCEPROP 2 LAST $XR0 21G10< 
J 0
(-6845 250);
DISPLAY 0.638298 (-6845 250);
PAINT MONO (-6845 250);
FORCEPROP 1 LAST BODY_TYPE COMMENT
J 0
(-6890 385);
DISPLAY 0.808511 (-6890 385);
PAINT GREEN (-6890 385);
DISPLAY INVISIBLE (-6890 385);
FORCEPROP 1 LAST CDS_LMAN_SYM_OUTLINE -50,50,50,-50
J 0
(-6900 250);
DISPLAY 0.468085 (-6900 250);
PAINT GREEN (-6900 250);
DISPLAY INVISIBLE (-6900 250);
FORCEPROP 2 LAST CDS_LIB cls
J 0
(-6900 250);
DISPLAY INVISIBLE (-6900 250);
FORCEPROP 1 LAST OFFPAGE TRUE
J 0
(-6890 305);
DISPLAY 0.808511 (-6890 305);
PAINT GREEN (-6890 305);
DISPLAY INVISIBLE (-6890 305);
FORCEPROP 2 LAST PATH I203
J 0
(-6850 350);
DISPLAY 1.021277 (-6850 350);
DISPLAY INVISIBLE (-6850 350);
FORCEADD RESISTOR..1
(-4150 100);
FORCEPROP 1 LAST $LOCATION R266
J 2
(-4350 100);
DISPLAY 1.212766 (-4350 100);
PAINT GREEN (-4350 100);
FORCEPROP 0 LAST CDS_LOCATION R266
J 0
(-3950 200);
DISPLAY 1.021277 (-3950 200);
DISPLAY INVISIBLE (-3950 200);
FORCEPROP 0 LAST $SEC 1
J 0
(-3950 200);
DISPLAY 0.680851 (-3950 200);
PAINT MONO (-3950 200);
DISPLAY INVISIBLE (-3950 200);
FORCEPROP 0 LAST CDS_SEC 1
J 0
(-3950 200);
DISPLAY 1.021277 (-3950 200);
DISPLAY INVISIBLE (-3950 200);
FORCEPROP 0 LASTPIN (-4250 100) $PN 1
J 2
(-4260 110);
DISPLAY 0.680851 (-4260 110);
PAINT MONO (-4260 110);
FORCEPROP 0 LASTPIN (-4000 100) $PN 2
J 0
(-3990 110);
DISPLAY 0.680851 (-3990 110);
PAINT MONO (-3990 110);
FORCEPROP 0 LAST PACKAGE 0402
J 0
(-4200 150);
DISPLAY 1.021277 (-4200 150);
FORCEPROP 1 LAST VALUE 33OHM
J 0
(-3950 100);
DISPLAY 1.234043 (-3950 100);
PAINT GREEN (-3950 100);
FORCEPROP 0 LAST NO_ASSY TRUE
J 0
(-4400 0);
DISPLAY 1.021277 (-4400 0);
DISPLAY BOTH (-4400 0);
FORCEPROP 2 LAST CDS_LIB passive
J 0
(-4150 100);
DISPLAY INVISIBLE (-4150 100);
FORCEPROP 1 LAST CDS_LMAN_SYM_OUTLINE -50,50,100,-50
J 0
(-4150 100);
DISPLAY 0.468085 (-4150 100);
PAINT GREEN (-4150 100);
DISPLAY INVISIBLE (-4150 100);
FORCEPROP 2 LAST SIGNAL_MODEL DEFAULT_RESISTOR_33OHM_2_1
J 0
(-4300 300);
DISPLAY 1.021277 (-4300 300);
DISPLAY INVISIBLE (-4300 300);
FORCEPROP 1 LAST CLS_PN G155-133R0-01
J 0
(-4286 300);
DISPLAY 1.212766 (-4286 300);
PAINT GREEN (-4286 300);
DISPLAY INVISIBLE (-4286 300);
FORCEPROP 1 LAST TOLERANCE 1%
J 0
(-4347 355);
DISPLAY 1.212766 (-4347 355);
PAINT GREEN (-4347 355);
DISPLAY INVISIBLE (-4347 355);
FORCEPROP 1 LAST PATH I204
J 0
(-4347 205);
DISPLAY 1.212766 (-4347 205);
PAINT GREEN (-4347 205);
DISPLAY INVISIBLE (-4347 205);
FORCEADD OFFPAGE_IN..2
R 2
(-5750 100);
FORCEPROP 2 LAST $XR0 12H5> 
J 0
(-5933 100);
DISPLAY 0.638298 (-5933 100);
PAINT MONO (-5933 100);
FORCEPROP 2 LAST CDS_LIB cls
J 0
(-5750 100);
DISPLAY INVISIBLE (-5750 100);
FORCEPROP 1 LAST CDS_LMAN_SYM_OUTLINE -50,50,50,-50
J 2
(-5750 100);
DISPLAY 0.468085 (-5750 100);
PAINT GREEN (-5750 100);
DISPLAY INVISIBLE (-5750 100);
FORCEPROP 1 LAST BODY_TYPE COMMENT
J 2
(-5760 235);
DISPLAY 0.808511 (-5760 235);
PAINT GREEN (-5760 235);
DISPLAY INVISIBLE (-5760 235);
FORCEPROP 1 LAST OFFPAGE TRUE
J 2
(-5760 155);
DISPLAY 0.808511 (-5760 155);
PAINT GREEN (-5760 155);
DISPLAY INVISIBLE (-5760 155);
FORCEPROP 2 LAST PATH I205
J 0
(-5700 200);
DISPLAY 1.021277 (-5700 200);
DISPLAY INVISIBLE (-5700 200);
FORCEADD RESISTOR..1
(1300 3800);
FORCEPROP 1 LAST $LOCATION R267
J 2
(1199 3855);
DISPLAY 1.212766 (1199 3855);
PAINT GREEN (1199 3855);
FORCEPROP 0 LAST CDS_LOCATION R267
J 0
(1400 3950);
DISPLAY 1.021277 (1400 3950);
DISPLAY INVISIBLE (1400 3950);
FORCEPROP 0 LAST $SEC 1
J 0
(1400 3950);
DISPLAY 0.680851 (1400 3950);
PAINT MONO (1400 3950);
DISPLAY INVISIBLE (1400 3950);
FORCEPROP 0 LAST CDS_SEC 1
J 0
(1400 3950);
DISPLAY 1.021277 (1400 3950);
DISPLAY INVISIBLE (1400 3950);
FORCEPROP 0 LASTPIN (1200 3800) $PN 1
J 2
(1190 3810);
DISPLAY 0.680851 (1190 3810);
PAINT MONO (1190 3810);
FORCEPROP 0 LASTPIN (1450 3800) $PN 2
J 0
(1460 3810);
DISPLAY 0.680851 (1460 3810);
PAINT MONO (1460 3810);
FORCEPROP 0 LAST PACKAGE 0402
J 0
(1200 3700);
DISPLAY 1.021277 (1200 3700);
FORCEPROP 1 LAST VALUE 33OHM
J 0
(1400 3850);
DISPLAY 1.234043 (1400 3850);
PAINT GREEN (1400 3850);
FORCEPROP 2 LAST CDS_LIB passive
J 0
(1300 3800);
DISPLAY INVISIBLE (1300 3800);
FORCEPROP 1 LAST CDS_LMAN_SYM_OUTLINE -50,50,100,-50
J 0
(1300 3800);
DISPLAY 0.468085 (1300 3800);
PAINT GREEN (1300 3800);
DISPLAY INVISIBLE (1300 3800);
FORCEPROP 2 LAST SIGNAL_MODEL DEFAULT_RESISTOR_33OHM_2_1
J 0
(1150 4000);
DISPLAY 1.021277 (1150 4000);
DISPLAY INVISIBLE (1150 4000);
FORCEPROP 1 LAST CLS_PN G155-133R0-01
J 0
(1164 4000);
DISPLAY 1.212766 (1164 4000);
PAINT GREEN (1164 4000);
DISPLAY INVISIBLE (1164 4000);
FORCEPROP 1 LAST TOLERANCE 1%
J 0
(1103 4055);
DISPLAY 1.212766 (1103 4055);
PAINT GREEN (1103 4055);
DISPLAY INVISIBLE (1103 4055);
FORCEPROP 1 LAST PATH I206
J 0
(1103 3905);
DISPLAY 1.212766 (1103 3905);
PAINT GREEN (1103 3905);
DISPLAY INVISIBLE (1103 3905);
FORCEPROP 2 LASTPIN (1200 3800) SIG_NAME UN$527$RESISTOR$I206$1
J 0
(1210 3810);
DISPLAY 0.659574 (1210 3810);
PAINT MONO (1210 3810);
DISPLAY INVISIBLE (1210 3810);
FORCEADD OFFPAGE_OUT..1
R 2
(550 2650);
FORCEPROP 2 LAST $XR0 12H5< 
J 0
(367 2650);
DISPLAY 0.638298 (367 2650);
PAINT MONO (367 2650);
FORCEPROP 1 LAST BODY_TYPE COMMENT
J 2
(540 2785);
DISPLAY 0.808511 (540 2785);
PAINT GREEN (540 2785);
DISPLAY INVISIBLE (540 2785);
FORCEPROP 1 LAST CDS_LMAN_SYM_OUTLINE -50,50,50,-50
J 2
(550 2650);
DISPLAY 0.468085 (550 2650);
PAINT GREEN (550 2650);
DISPLAY INVISIBLE (550 2650);
FORCEPROP 2 LAST CDS_LIB cls
J 0
(550 2650);
DISPLAY INVISIBLE (550 2650);
FORCEPROP 1 LAST OFFPAGE TRUE
J 2
(540 2705);
DISPLAY 0.808511 (540 2705);
PAINT GREEN (540 2705);
DISPLAY INVISIBLE (540 2705);
FORCEPROP 2 LAST PATH I207
J 0
(600 2750);
DISPLAY 1.021277 (600 2750);
DISPLAY INVISIBLE (600 2750);
FORCEADD CAPACITOR..2
(-8800 4550);
FORCEPROP 1 LAST $LOCATION C282
J 0
(-8750 4450);
DISPLAY 1.212766 (-8750 4450);
PAINT GREEN (-8750 4450);
FORCEPROP 0 LAST CDS_LOCATION C282
J 0
(-8700 4600);
DISPLAY 1.021277 (-8700 4600);
DISPLAY INVISIBLE (-8700 4600);
FORCEPROP 0 LAST $SEC 1
J 0
(-8700 4600);
DISPLAY 0.680851 (-8700 4600);
PAINT MONO (-8700 4600);
DISPLAY INVISIBLE (-8700 4600);
FORCEPROP 0 LAST CDS_SEC 1
J 0
(-8700 4600);
DISPLAY 1.021277 (-8700 4600);
DISPLAY INVISIBLE (-8700 4600);
FORCEPROP 0 LASTPIN (-8800 4650) $PN 1
R 1
J 0
(-8810 4660);
DISPLAY 0.680851 (-8810 4660);
PAINT MONO (-8810 4660);
FORCEPROP 0 LASTPIN (-8800 4400) $PN 2
R 1
J 2
(-8810 4390);
DISPLAY 0.680851 (-8810 4390);
PAINT MONO (-8810 4390);
FORCEPROP 1 LAST VALUE 10UF
J 0
(-8700 4550);
DISPLAY 1.212766 (-8700 4550);
PAINT GREEN (-8700 4550);
FORCEPROP 0 LAST PACKAGE 0805
J 0
(-8700 4650);
DISPLAY 1.021277 (-8700 4650);
FORCEPROP 0 LAST VOLTAGE 25V
J 0
(-8700 4750);
DISPLAY 1.021277 (-8700 4750);
FORCEPROP 1 LAST CLS_PN G107-0F106-EM
J 0
(-8900 4600);
DISPLAY 1.212766 (-8900 4600);
PAINT GREEN (-8900 4600);
DISPLAY INVISIBLE (-8900 4600);
FORCEPROP 1 LAST CDS_LMAN_SYM_OUTLINE -50,0,50,-50
J 0
(-8800 4550);
DISPLAY 0.468085 (-8800 4550);
PAINT GREEN (-8800 4550);
DISPLAY INVISIBLE (-8800 4550);
FORCEPROP 2 LAST CDS_LIB passive
J 0
(-8800 4550);
DISPLAY INVISIBLE (-8800 4550);
FORCEPROP 1 LAST TOLERANCE 20%
J 0
(-8950 4650);
DISPLAY 1.212766 (-8950 4650);
PAINT GREEN (-8950 4650);
DISPLAY INVISIBLE (-8950 4650);
FORCEPROP 1 LAST PATH I208
J 0
(-8900 4600);
DISPLAY 1.212766 (-8900 4600);
PAINT GREEN (-8900 4600);
DISPLAY INVISIBLE (-8900 4600);
FORCEADD CAPACITOR..2
(-8350 4550);
FORCEPROP 1 LAST $LOCATION C283
J 0
(-8250 4400);
DISPLAY 1.212766 (-8250 4400);
PAINT GREEN (-8250 4400);
FORCEPROP 0 LAST CDS_LOCATION C283
J 0
(-8250 4600);
DISPLAY 1.021277 (-8250 4600);
DISPLAY INVISIBLE (-8250 4600);
FORCEPROP 0 LAST $SEC 1
J 0
(-8250 4600);
DISPLAY 0.680851 (-8250 4600);
PAINT MONO (-8250 4600);
DISPLAY INVISIBLE (-8250 4600);
FORCEPROP 0 LAST CDS_SEC 1
J 0
(-8250 4600);
DISPLAY 1.021277 (-8250 4600);
DISPLAY INVISIBLE (-8250 4600);
FORCEPROP 0 LASTPIN (-8350 4650) $PN 1
R 1
J 0
(-8360 4660);
DISPLAY 0.680851 (-8360 4660);
PAINT MONO (-8360 4660);
FORCEPROP 0 LASTPIN (-8350 4400) $PN 2
R 1
J 2
(-8360 4390);
DISPLAY 0.680851 (-8360 4390);
PAINT MONO (-8360 4390);
FORCEPROP 0 LAST PACKAGE 0805
J 0
(-8250 4600);
DISPLAY 1.021277 (-8250 4600);
FORCEPROP 1 LAST VALUE 10UF
J 0
(-8250 4500);
DISPLAY 1.212766 (-8250 4500);
PAINT GREEN (-8250 4500);
FORCEPROP 0 LAST VOLTAGE 25V
J 0
(-8250 4700);
DISPLAY 1.021277 (-8250 4700);
FORCEPROP 1 LAST TOLERANCE 20%
J 0
(-8500 4650);
DISPLAY 1.212766 (-8500 4650);
PAINT GREEN (-8500 4650);
DISPLAY INVISIBLE (-8500 4650);
FORCEPROP 2 LAST CDS_LIB passive
J 0
(-8350 4550);
DISPLAY INVISIBLE (-8350 4550);
FORCEPROP 1 LAST CDS_LMAN_SYM_OUTLINE -50,0,50,-50
J 0
(-8350 4550);
DISPLAY 0.468085 (-8350 4550);
PAINT GREEN (-8350 4550);
DISPLAY INVISIBLE (-8350 4550);
FORCEPROP 1 LAST CLS_PN G107-0F106-EM
J 0
(-8450 4600);
DISPLAY 1.212766 (-8450 4600);
PAINT GREEN (-8450 4600);
DISPLAY INVISIBLE (-8450 4600);
FORCEPROP 1 LAST PATH I209
J 0
(-8450 4600);
DISPLAY 1.212766 (-8450 4600);
PAINT GREEN (-8450 4600);
DISPLAY INVISIBLE (-8450 4600);
FORCEADD VCC..1
(-8100 850);
FORCEPROP 3 LASTPIN (-8050 800) SIG_NAME XP5R0V_USB_CONN\g
J 0
(-8040 810);
DISPLAY 0.659574 (-8040 810);
PAINT MONO (-8040 810);
DISPLAY INVISIBLE (-8040 810);
FORCEPROP 0 LAST VOLTAGE 5V
J 0
(-8300 950);
DISPLAY BOTH (-8300 950);
FORCEPROP 1 LAST HDL_POWER XP5R0V_USB_CONN
J 1
(-8045 905);
DISPLAY 0.808511 (-8045 905);
PAINT GREEN (-8045 905);
FORCEPROP 2 LAST CDS_LIB cls
J 0
(-8100 850);
DISPLAY INVISIBLE (-8100 850);
FORCEPROP 1 LAST CDS_LMAN_SYM_OUTLINE -250,250,250,-250
J 0
(-8100 850);
DISPLAY 0.468085 (-8100 850);
PAINT GREEN (-8100 850);
DISPLAY INVISIBLE (-8100 850);
FORCEPROP 1 LAST BODY_TYPE PLUMBING
J 0
(-8145 807);
DISPLAY 0.340426 (-8145 807);
PAINT GREEN (-8145 807);
DISPLAY INVISIBLE (-8145 807);
FORCEPROP 1 LAST PATH I21
J 0
(-8065 940);
DISPLAY 0.808511 (-8065 940);
PAINT GREEN (-8065 940);
DISPLAY INVISIBLE (-8065 940);
FORCEADD OFFPAGE_IN..2
R 2
(-5750 250);
FORCEPROP 2 LAST $XR1 21G10< 
J 0
(-6143 250);
DISPLAY 0.638298 (-6143 250);
PAINT MONO (-6143 250);
FORCEPROP 2 LAST $XR0 21L6> 
J 0
(-5933 250);
DISPLAY 0.638298 (-5933 250);
PAINT MONO (-5933 250);
FORCEPROP 1 LAST BODY_TYPE COMMENT
J 2
(-5760 385);
DISPLAY 0.808511 (-5760 385);
PAINT GREEN (-5760 385);
DISPLAY INVISIBLE (-5760 385);
FORCEPROP 1 LAST CDS_LMAN_SYM_OUTLINE -50,50,50,-50
J 2
(-5750 250);
DISPLAY 0.468085 (-5750 250);
PAINT GREEN (-5750 250);
DISPLAY INVISIBLE (-5750 250);
FORCEPROP 2 LAST CDS_LIB cls
J 0
(-5750 250);
DISPLAY INVISIBLE (-5750 250);
FORCEPROP 1 LAST OFFPAGE TRUE
J 2
(-5760 305);
DISPLAY 0.808511 (-5760 305);
PAINT GREEN (-5760 305);
DISPLAY INVISIBLE (-5760 305);
FORCEPROP 2 LAST PATH I210
J 0
(-5700 350);
DISPLAY 1.021277 (-5700 350);
DISPLAY INVISIBLE (-5700 350);
FORCEADD RESISTOR..1
(-1950 6700);
FORCEPROP 1 LAST $LOCATION R287
J 2
(-2100 6700);
DISPLAY 1.212766 (-2100 6700);
PAINT GREEN (-2100 6700);
FORCEPROP 0 LAST CDS_LOCATION R287
J 0
(-1750 6800);
DISPLAY 1.021277 (-1750 6800);
DISPLAY INVISIBLE (-1750 6800);
FORCEPROP 0 LAST $SEC 1
J 0
(-1750 6800);
DISPLAY 0.680851 (-1750 6800);
PAINT MONO (-1750 6800);
DISPLAY INVISIBLE (-1750 6800);
FORCEPROP 0 LAST CDS_SEC 1
J 0
(-1750 6800);
DISPLAY 1.021277 (-1750 6800);
DISPLAY INVISIBLE (-1750 6800);
FORCEPROP 0 LASTPIN (-2050 6700) $PN 1
J 2
(-2060 6710);
DISPLAY 0.680851 (-2060 6710);
PAINT MONO (-2060 6710);
FORCEPROP 0 LASTPIN (-1800 6700) $PN 2
J 0
(-1790 6710);
DISPLAY 0.680851 (-1790 6710);
PAINT MONO (-1790 6710);
FORCEPROP 1 LAST VALUE 4.7KOHM
J 0
(-1700 6700);
DISPLAY 1.234043 (-1700 6700);
PAINT GREEN (-1700 6700);
FORCEPROP 0 LAST PACKAGE 0402
J 0
(-2000 6750);
DISPLAY 1.021277 (-2000 6750);
FORCEPROP 1 LAST CLS_PN G155-14701-01
J 0
(-2086 6900);
DISPLAY 1.212766 (-2086 6900);
PAINT GREEN (-2086 6900);
DISPLAY INVISIBLE (-2086 6900);
FORCEPROP 2 LAST CDS_LIB passive
J 0
(-1950 6700);
DISPLAY INVISIBLE (-1950 6700);
FORCEPROP 1 LAST CDS_LMAN_SYM_OUTLINE -50,50,100,-50
J 0
(-1950 6700);
DISPLAY 0.468085 (-1950 6700);
PAINT GREEN (-1950 6700);
DISPLAY INVISIBLE (-1950 6700);
FORCEPROP 1 LAST TOLERANCE 1%
J 0
(-2147 6955);
DISPLAY 1.212766 (-2147 6955);
PAINT GREEN (-2147 6955);
DISPLAY INVISIBLE (-2147 6955);
FORCEPROP 1 LAST PATH I211
J 0
(-2147 6805);
DISPLAY 1.212766 (-2147 6805);
PAINT GREEN (-2147 6805);
DISPLAY INVISIBLE (-2147 6805);
FORCEADD VCC..1
(-1300 6850);
FORCEPROP 3 LASTPIN (-1250 6800) SIG_NAME XP3R3V_FPGA\g
J 0
(-1240 6810);
DISPLAY 0.659574 (-1240 6810);
PAINT MONO (-1240 6810);
DISPLAY INVISIBLE (-1240 6810);
FORCEPROP 1 LAST HDL_POWER XP3R3V_FPGA
J 1
(-1245 6905);
DISPLAY 1.021277 (-1245 6905);
PAINT GREEN (-1245 6905);
FORCEPROP 0 LAST VOLTAGE 3.3V
J 0
(-1550 7000);
DISPLAY 1.021277 (-1550 7000);
DISPLAY BOTH (-1550 7000);
FORCEPROP 2 LAST CDS_LIB cls
J 0
(-1300 6850);
DISPLAY INVISIBLE (-1300 6850);
FORCEPROP 1 LAST CDS_LMAN_SYM_OUTLINE -250,250,250,-250
J 0
(-1300 6850);
DISPLAY 0.468085 (-1300 6850);
PAINT GREEN (-1300 6850);
DISPLAY INVISIBLE (-1300 6850);
FORCEPROP 1 LAST BODY_TYPE PLUMBING
J 0
(-1345 6807);
DISPLAY 0.340426 (-1345 6807);
PAINT GREEN (-1345 6807);
DISPLAY INVISIBLE (-1345 6807);
FORCEPROP 1 LAST PATH I212
J 0
(-1265 6940);
DISPLAY 0.808511 (-1265 6940);
PAINT GREEN (-1265 6940);
DISPLAY INVISIBLE (-1265 6940);
FORCEADD GND_SG..1
(-4500 6350);
FORCEPROP 3 LASTPIN (-4450 6400) SIG_NAME SG\g
J 0
(-4440 6410);
DISPLAY 0.659574 (-4440 6410);
PAINT MONO (-4440 6410);
DISPLAY INVISIBLE (-4440 6410);
FORCEPROP 1 LAST HDL_POWER SG
J 1
(-4450 6250);
DISPLAY 0.808511 (-4450 6250);
PAINT GREEN (-4450 6250);
FORCEPROP 2 LAST CDS_LIB cls
J 0
(-4500 6350);
DISPLAY INVISIBLE (-4500 6350);
FORCEPROP 1 LAST CDS_LMAN_SYM_OUTLINE 0,0,100,-50
J 0
(-4500 6350);
DISPLAY 0.468085 (-4500 6350);
PAINT GREEN (-4500 6350);
DISPLAY INVISIBLE (-4500 6350);
FORCEPROP 1 LAST BODY_TYPE PLUMBING
J 0
(-4485 6335);
DISPLAY 0.808511 (-4485 6335);
PAINT GREEN (-4485 6335);
DISPLAY INVISIBLE (-4485 6335);
FORCEPROP 1 LAST PATH I22
J 0
(-4465 6350);
DISPLAY 0.808511 (-4465 6350);
PAINT GREEN (-4465 6350);
DISPLAY INVISIBLE (-4465 6350);
FORCEADD NUT..1
R 2
(-11000 2800);
FORCEPROP 1 LAST $LOCATION MAC_PIN8
J 2
(-11100 2850);
DISPLAY 1.212766 (-11100 2850);
PAINT GREEN (-11100 2850);
FORCEPROP 0 LAST CDS_LOCATION MAC_PIN8
J 2
(-11100 2850);
DISPLAY 1.212766 (-11100 2850);
PAINT GREEN (-11100 2850);
DISPLAY INVISIBLE (-11100 2850);
FORCEPROP 0 LAST $SEC 1
J 0
(-11100 2950);
DISPLAY 0.680851 (-11100 2950);
PAINT MONO (-11100 2950);
DISPLAY INVISIBLE (-11100 2950);
FORCEPROP 0 LAST CDS_SEC 1
J 0
(-11100 2950);
DISPLAY 1.021277 (-11100 2950);
DISPLAY INVISIBLE (-11100 2950);
FORCEPROP 0 LASTPIN (-10850 2800) $PN 1
J 0
(-10840 2810);
DISPLAY 0.680851 (-10840 2810);
PAINT MONO (-10840 2810);
FORCEPROP 0 LAST PART_NUMBER 0332-0-43-80-18-27-10-0
J 0
(-12200 2700);
DISPLAY 1.021277 (-12200 2700);
FORCEPROP 1 LAST CLS_PN A200-00029-FB
J 2
(-11150 2750);
DISPLAY 1.212766 (-11150 2750);
PAINT GREEN (-11150 2750);
FORCEPROP 1 LAST CDS_LMAN_SYM_OUTLINE -50,50,50,-50
J 2
(-11000 2800);
DISPLAY 0.468085 (-11000 2800);
PAINT GREEN (-11000 2800);
DISPLAY INVISIBLE (-11000 2800);
FORCEPROP 2 LAST CDS_LIB mech
J 2
(-11000 2800);
DISPLAY INVISIBLE (-11000 2800);
FORCEPROP 1 LAST PATH I220
J 2
(-10900 2970);
DISPLAY 1.212766 (-10900 2970);
PAINT GREEN (-10900 2970);
DISPLAY INVISIBLE (-10900 2970);
FORCEADD RESISTOR..2
R 1
(-9100 2400);
FORCEPROP 1 LAST $LOCATION R265
J 0
(-9500 2400);
DISPLAY 1.212766 (-9500 2400);
PAINT GREEN (-9500 2400);
FORCEPROP 0 LAST CDS_LOCATION R265
R 1
J 0
(-8900 2500);
DISPLAY 1.021277 (-8900 2500);
DISPLAY INVISIBLE (-8900 2500);
FORCEPROP 0 LAST $SEC 1
R 1
J 0
(-8900 2500);
DISPLAY 0.680851 (-8900 2500);
PAINT MONO (-8900 2500);
DISPLAY INVISIBLE (-8900 2500);
FORCEPROP 0 LAST CDS_SEC 1
R 1
J 0
(-8900 2500);
DISPLAY 1.021277 (-8900 2500);
DISPLAY INVISIBLE (-8900 2500);
FORCEPROP 0 LASTPIN (-9200 2400) $PN 1
J 2
(-9210 2410);
DISPLAY 0.680851 (-9210 2410);
PAINT MONO (-9210 2410);
FORCEPROP 0 LASTPIN (-8950 2400) $PN 2
J 0
(-8940 2410);
DISPLAY 0.680851 (-8940 2410);
PAINT MONO (-8940 2410);
FORCEPROP 1 LAST VALUE 100KOHM
J 0
(-8900 2400);
DISPLAY 1.212766 (-8900 2400);
PAINT GREEN (-8900 2400);
FORCEPROP 0 LAST PACKAGE 0402
J 0
(-9150 2300);
DISPLAY 1.021277 (-9150 2300);
FORCEPROP 1 LAST CLS_PN G155-11003-01
R 1
J 0
(-9300 2264);
DISPLAY 1.212766 (-9300 2264);
PAINT GREEN (-9300 2264);
DISPLAY INVISIBLE (-9300 2264);
FORCEPROP 1 LAST CDS_LMAN_SYM_OUTLINE -50,50,50,-100
R 1
J 0
(-9100 2400);
DISPLAY 0.468085 (-9100 2400);
PAINT GREEN (-9100 2400);
DISPLAY INVISIBLE (-9100 2400);
FORCEPROP 2 LAST CDS_LIB passive
R 1
J 0
(-9100 2400);
DISPLAY INVISIBLE (-9100 2400);
FORCEPROP 1 LAST TOLERANCE 1%
R 1
J 0
(-9355 2203);
DISPLAY 1.212766 (-9355 2203);
PAINT GREEN (-9355 2203);
DISPLAY INVISIBLE (-9355 2203);
FORCEPROP 1 LAST PATH I221
R 1
J 0
(-9205 2203);
DISPLAY 1.212766 (-9205 2203);
PAINT GREEN (-9205 2203);
DISPLAY INVISIBLE (-9205 2203);
FORCEADD RESISTOR..2
R 1
(-9100 2500);
FORCEPROP 1 LAST $LOCATION R264
J 0
(-9500 2500);
DISPLAY 1.212766 (-9500 2500);
PAINT GREEN (-9500 2500);
FORCEPROP 0 LAST CDS_LOCATION R264
R 1
J 0
(-8900 2600);
DISPLAY 1.021277 (-8900 2600);
DISPLAY INVISIBLE (-8900 2600);
FORCEPROP 0 LAST $SEC 1
R 1
J 0
(-8900 2600);
DISPLAY 0.680851 (-8900 2600);
PAINT MONO (-8900 2600);
DISPLAY INVISIBLE (-8900 2600);
FORCEPROP 0 LAST CDS_SEC 1
R 1
J 0
(-8900 2600);
DISPLAY 1.021277 (-8900 2600);
DISPLAY INVISIBLE (-8900 2600);
FORCEPROP 0 LASTPIN (-9200 2500) $PN 1
J 2
(-9210 2510);
DISPLAY 0.680851 (-9210 2510);
PAINT MONO (-9210 2510);
FORCEPROP 0 LASTPIN (-8950 2500) $PN 2
J 0
(-8940 2510);
DISPLAY 0.680851 (-8940 2510);
PAINT MONO (-8940 2510);
FORCEPROP 1 LAST VALUE 100KOHM
J 0
(-8900 2500);
DISPLAY 1.212766 (-8900 2500);
PAINT GREEN (-8900 2500);
FORCEPROP 0 LAST PACKAGE 0402
J 0
(-9150 2550);
DISPLAY 1.021277 (-9150 2550);
FORCEPROP 1 LAST CLS_PN G155-11003-01
R 1
J 0
(-9300 2364);
DISPLAY 1.212766 (-9300 2364);
PAINT GREEN (-9300 2364);
DISPLAY INVISIBLE (-9300 2364);
FORCEPROP 2 LAST CDS_LIB passive
R 1
J 0
(-9100 2500);
DISPLAY INVISIBLE (-9100 2500);
FORCEPROP 1 LAST CDS_LMAN_SYM_OUTLINE -50,50,50,-100
R 1
J 0
(-9100 2500);
DISPLAY 0.468085 (-9100 2500);
PAINT GREEN (-9100 2500);
DISPLAY INVISIBLE (-9100 2500);
FORCEPROP 1 LAST TOLERANCE 1%
R 1
J 0
(-9355 2303);
DISPLAY 1.212766 (-9355 2303);
PAINT GREEN (-9355 2303);
DISPLAY INVISIBLE (-9355 2303);
FORCEPROP 1 LAST PATH I222
R 1
J 0
(-9205 2303);
DISPLAY 1.212766 (-9205 2303);
PAINT GREEN (-9205 2303);
DISPLAY INVISIBLE (-9205 2303);
FORCEADD VCC..1
(-9950 2500);
FORCEPROP 3 LASTPIN (-9900 2450) SIG_NAME XP3R3V_FPGA\g
J 0
(-9890 2460);
DISPLAY 0.659574 (-9890 2460);
PAINT MONO (-9890 2460);
DISPLAY INVISIBLE (-9890 2460);
FORCEPROP 1 LAST HDL_POWER XP3R3V_FPGA
J 1
(-9895 2555);
DISPLAY 1.021277 (-9895 2555);
PAINT GREEN (-9895 2555);
FORCEPROP 0 LAST VOLTAGE 3.3V
J 0
(-10200 2600);
DISPLAY 1.021277 (-10200 2600);
DISPLAY BOTH (-10200 2600);
FORCEPROP 1 LAST CDS_LMAN_SYM_OUTLINE -250,250,250,-250
J 0
(-9950 2500);
DISPLAY 0.468085 (-9950 2500);
PAINT GREEN (-9950 2500);
DISPLAY INVISIBLE (-9950 2500);
FORCEPROP 2 LAST CDS_LIB cls
J 0
(-9950 2500);
DISPLAY INVISIBLE (-9950 2500);
FORCEPROP 1 LAST BODY_TYPE PLUMBING
J 0
(-9995 2457);
DISPLAY 0.340426 (-9995 2457);
PAINT GREEN (-9995 2457);
DISPLAY INVISIBLE (-9995 2457);
FORCEPROP 1 LAST PATH I223
J 0
(-9915 2590);
DISPLAY 0.808511 (-9915 2590);
PAINT GREEN (-9915 2590);
DISPLAY INVISIBLE (-9915 2590);
FORCEADD NUT..1
R 2
(-11000 3050);
FORCEPROP 1 LAST $LOCATION MAC_PIN7
J 2
(-11100 3100);
DISPLAY 1.212766 (-11100 3100);
PAINT GREEN (-11100 3100);
FORCEPROP 0 LAST CDS_LOCATION MAC_PIN7
J 2
(-11100 3100);
DISPLAY 1.212766 (-11100 3100);
PAINT GREEN (-11100 3100);
DISPLAY INVISIBLE (-11100 3100);
FORCEPROP 0 LAST $SEC 1
J 0
(-11100 3200);
DISPLAY 0.680851 (-11100 3200);
PAINT MONO (-11100 3200);
DISPLAY INVISIBLE (-11100 3200);
FORCEPROP 0 LAST CDS_SEC 1
J 0
(-11100 3200);
DISPLAY 1.021277 (-11100 3200);
DISPLAY INVISIBLE (-11100 3200);
FORCEPROP 0 LASTPIN (-10850 3050) $PN 1
J 0
(-10840 3060);
DISPLAY 0.680851 (-10840 3060);
PAINT MONO (-10840 3060);
FORCEPROP 1 LAST CLS_PN A200-00029-FB
J 2
(-11150 3000);
DISPLAY 1.212766 (-11150 3000);
PAINT GREEN (-11150 3000);
FORCEPROP 0 LAST PART_NUMBER 0332-0-43-80-18-27-10-0
J 0
(-12200 2950);
DISPLAY 1.021277 (-12200 2950);
FORCEPROP 2 LAST CDS_LIB mech
J 0
(-11000 3050);
DISPLAY INVISIBLE (-11000 3050);
FORCEPROP 1 LAST CDS_LMAN_SYM_OUTLINE -50,50,50,-50
J 2
(-11000 3050);
DISPLAY 0.468085 (-11000 3050);
PAINT GREEN (-11000 3050);
DISPLAY INVISIBLE (-11000 3050);
FORCEPROP 1 LAST PATH I224
J 2
(-10900 3220);
DISPLAY 1.212766 (-10900 3220);
PAINT GREEN (-10900 3220);
DISPLAY INVISIBLE (-10900 3220);
FORCEADD NUT..1
R 2
(-11000 3300);
FORCEPROP 1 LAST $LOCATION MAC_PIN6
J 2
(-11100 3350);
DISPLAY 1.212766 (-11100 3350);
PAINT GREEN (-11100 3350);
FORCEPROP 0 LAST CDS_LOCATION MAC_PIN6
J 2
(-11100 3350);
DISPLAY 1.212766 (-11100 3350);
PAINT GREEN (-11100 3350);
DISPLAY INVISIBLE (-11100 3350);
FORCEPROP 0 LAST $SEC 1
J 0
(-11100 3450);
DISPLAY 0.680851 (-11100 3450);
PAINT MONO (-11100 3450);
DISPLAY INVISIBLE (-11100 3450);
FORCEPROP 0 LAST CDS_SEC 1
J 0
(-11100 3450);
DISPLAY 1.021277 (-11100 3450);
DISPLAY INVISIBLE (-11100 3450);
FORCEPROP 0 LASTPIN (-10850 3300) $PN 1
J 0
(-10840 3310);
DISPLAY 0.680851 (-10840 3310);
PAINT MONO (-10840 3310);
FORCEPROP 1 LAST CLS_PN A200-00029-FB
J 2
(-11150 3250);
DISPLAY 1.212766 (-11150 3250);
PAINT GREEN (-11150 3250);
FORCEPROP 0 LAST PART_NUMBER 0332-0-43-80-18-27-10-0
J 0
(-12200 3200);
DISPLAY 1.021277 (-12200 3200);
FORCEPROP 2 LAST CDS_LIB mech
J 0
(-11000 3300);
DISPLAY INVISIBLE (-11000 3300);
FORCEPROP 1 LAST CDS_LMAN_SYM_OUTLINE -50,50,50,-50
J 2
(-11000 3300);
DISPLAY 0.468085 (-11000 3300);
PAINT GREEN (-11000 3300);
DISPLAY INVISIBLE (-11000 3300);
FORCEPROP 1 LAST PATH I225
J 2
(-10900 3470);
DISPLAY 1.212766 (-10900 3470);
PAINT GREEN (-10900 3470);
DISPLAY INVISIBLE (-10900 3470);
FORCEADD NUT..1
R 2
(-11000 3550);
FORCEPROP 1 LAST $LOCATION MAC_PIN3
J 2
(-11100 3600);
DISPLAY 1.212766 (-11100 3600);
PAINT GREEN (-11100 3600);
FORCEPROP 0 LAST CDS_LOCATION MAC_PIN3
J 2
(-11100 3600);
DISPLAY 1.212766 (-11100 3600);
PAINT GREEN (-11100 3600);
DISPLAY INVISIBLE (-11100 3600);
FORCEPROP 0 LAST $SEC 1
J 0
(-11100 3700);
DISPLAY 0.680851 (-11100 3700);
PAINT MONO (-11100 3700);
DISPLAY INVISIBLE (-11100 3700);
FORCEPROP 0 LAST CDS_SEC 1
J 0
(-11100 3700);
DISPLAY 1.021277 (-11100 3700);
DISPLAY INVISIBLE (-11100 3700);
FORCEPROP 0 LASTPIN (-10850 3550) $PN 1
J 0
(-10840 3560);
DISPLAY 0.680851 (-10840 3560);
PAINT MONO (-10840 3560);
FORCEPROP 1 LAST CLS_PN A200-00029-FB
J 2
(-11150 3500);
DISPLAY 1.212766 (-11150 3500);
PAINT GREEN (-11150 3500);
FORCEPROP 0 LAST PART_NUMBER 0332-0-43-80-18-27-10-0
J 0
(-12200 3450);
DISPLAY 1.021277 (-12200 3450);
FORCEPROP 2 LAST CDS_LIB mech
J 0
(-11000 3550);
DISPLAY INVISIBLE (-11000 3550);
FORCEPROP 1 LAST CDS_LMAN_SYM_OUTLINE -50,50,50,-50
J 2
(-11000 3550);
DISPLAY 0.468085 (-11000 3550);
PAINT GREEN (-11000 3550);
DISPLAY INVISIBLE (-11000 3550);
FORCEPROP 1 LAST PATH I226
J 2
(-10900 3720);
DISPLAY 1.212766 (-10900 3720);
PAINT GREEN (-10900 3720);
DISPLAY INVISIBLE (-10900 3720);
FORCEADD NUT..1
R 2
(-11000 3800);
FORCEPROP 1 LAST $LOCATION MAC_PIN1
J 2
(-11100 3850);
DISPLAY 1.212766 (-11100 3850);
PAINT GREEN (-11100 3850);
FORCEPROP 0 LAST CDS_LOCATION MAC_PIN1
J 2
(-11100 3850);
DISPLAY 1.212766 (-11100 3850);
PAINT GREEN (-11100 3850);
DISPLAY INVISIBLE (-11100 3850);
FORCEPROP 0 LAST $SEC 1
J 0
(-11100 3950);
DISPLAY 0.680851 (-11100 3950);
PAINT MONO (-11100 3950);
DISPLAY INVISIBLE (-11100 3950);
FORCEPROP 0 LAST CDS_SEC 1
J 0
(-11100 3950);
DISPLAY 1.021277 (-11100 3950);
DISPLAY INVISIBLE (-11100 3950);
FORCEPROP 0 LASTPIN (-10850 3800) $PN 1
J 0
(-10840 3810);
DISPLAY 0.680851 (-10840 3810);
PAINT MONO (-10840 3810);
FORCEPROP 0 LAST PART_NUMBER 0332-0-43-80-18-27-10-0
J 0
(-12200 3700);
DISPLAY 1.021277 (-12200 3700);
FORCEPROP 1 LAST CLS_PN A200-00029-FB
J 2
(-11150 3750);
DISPLAY 1.212766 (-11150 3750);
PAINT GREEN (-11150 3750);
FORCEPROP 2 LAST CDS_LIB mech
J 0
(-11000 3800);
DISPLAY INVISIBLE (-11000 3800);
FORCEPROP 1 LAST CDS_LMAN_SYM_OUTLINE -50,50,50,-50
J 2
(-11000 3800);
DISPLAY 0.468085 (-11000 3800);
PAINT GREEN (-11000 3800);
DISPLAY INVISIBLE (-11000 3800);
FORCEPROP 1 LAST PATH I227
J 2
(-10900 3970);
DISPLAY 1.212766 (-10900 3970);
PAINT GREEN (-10900 3970);
DISPLAY INVISIBLE (-10900 3970);
FORCEADD NUT..1
R 2
(-11000 4150);
FORCEPROP 1 LAST $LOCATION MAC_PIN4
J 2
(-11100 4200);
DISPLAY 1.212766 (-11100 4200);
PAINT GREEN (-11100 4200);
FORCEPROP 0 LAST CDS_LOCATION MAC_PIN4
J 2
(-11100 4200);
DISPLAY 1.212766 (-11100 4200);
PAINT GREEN (-11100 4200);
DISPLAY INVISIBLE (-11100 4200);
FORCEPROP 0 LAST $SEC 1
J 0
(-11100 4300);
DISPLAY 0.680851 (-11100 4300);
PAINT MONO (-11100 4300);
DISPLAY INVISIBLE (-11100 4300);
FORCEPROP 0 LAST CDS_SEC 1
J 0
(-11100 4300);
DISPLAY 1.021277 (-11100 4300);
DISPLAY INVISIBLE (-11100 4300);
FORCEPROP 0 LASTPIN (-10850 4150) $PN 1
J 0
(-10840 4160);
DISPLAY 0.680851 (-10840 4160);
PAINT MONO (-10840 4160);
FORCEPROP 0 LAST PART_NUMBER 0332-0-43-80-18-27-10-0
J 0
(-12200 4050);
DISPLAY 1.021277 (-12200 4050);
FORCEPROP 1 LAST CLS_PN A200-00029-FB
J 2
(-11150 4100);
DISPLAY 1.212766 (-11150 4100);
PAINT GREEN (-11150 4100);
FORCEPROP 1 LAST CDS_LMAN_SYM_OUTLINE -50,50,50,-50
J 2
(-11000 4150);
DISPLAY 0.468085 (-11000 4150);
PAINT GREEN (-11000 4150);
DISPLAY INVISIBLE (-11000 4150);
FORCEPROP 2 LAST CDS_LIB mech
J 0
(-11000 4150);
DISPLAY INVISIBLE (-11000 4150);
FORCEPROP 1 LAST PATH I228
J 2
(-10900 4320);
DISPLAY 1.212766 (-10900 4320);
PAINT GREEN (-10900 4320);
DISPLAY INVISIBLE (-10900 4320);
FORCEADD NUT..1
R 2
(-11000 4400);
FORCEPROP 1 LAST $LOCATION MAC_PIN2
J 2
(-11100 4450);
DISPLAY 1.212766 (-11100 4450);
PAINT GREEN (-11100 4450);
FORCEPROP 0 LAST CDS_LOCATION MAC_PIN2
J 2
(-11100 4450);
DISPLAY 1.212766 (-11100 4450);
PAINT GREEN (-11100 4450);
DISPLAY INVISIBLE (-11100 4450);
FORCEPROP 0 LAST $SEC 1
J 0
(-11100 4550);
DISPLAY 0.680851 (-11100 4550);
PAINT MONO (-11100 4550);
DISPLAY INVISIBLE (-11100 4550);
FORCEPROP 0 LAST CDS_SEC 1
J 0
(-11100 4550);
DISPLAY 1.021277 (-11100 4550);
DISPLAY INVISIBLE (-11100 4550);
FORCEPROP 0 LASTPIN (-10850 4400) $PN 1
J 0
(-10840 4410);
DISPLAY 0.680851 (-10840 4410);
PAINT MONO (-10840 4410);
FORCEPROP 1 LAST CLS_PN A200-00029-FB
J 2
(-11150 4350);
DISPLAY 1.212766 (-11150 4350);
PAINT GREEN (-11150 4350);
FORCEPROP 0 LAST PART_NUMBER 0332-0-43-80-18-27-10-0
J 0
(-12200 4300);
DISPLAY 1.021277 (-12200 4300);
FORCEPROP 2 LAST CDS_LIB mech
J 0
(-11000 4400);
DISPLAY INVISIBLE (-11000 4400);
FORCEPROP 1 LAST CDS_LMAN_SYM_OUTLINE -50,50,50,-50
J 2
(-11000 4400);
DISPLAY 0.468085 (-11000 4400);
PAINT GREEN (-11000 4400);
DISPLAY INVISIBLE (-11000 4400);
FORCEPROP 1 LAST PATH I229
J 2
(-10900 4570);
DISPLAY 1.212766 (-10900 4570);
PAINT GREEN (-10900 4570);
DISPLAY INVISIBLE (-10900 4570);
FORCEADD RESISTOR..1
(-2950 6550);
FORCEPROP 1 LAST $LOCATION R96
J 2
(-3100 6550);
DISPLAY 1.212766 (-3100 6550);
PAINT GREEN (-3100 6550);
FORCEPROP 0 LAST CDS_LOCATION R96
J 0
(-2750 6650);
DISPLAY 1.021277 (-2750 6650);
DISPLAY INVISIBLE (-2750 6650);
FORCEPROP 0 LAST $SEC 1
J 0
(-2750 6650);
DISPLAY 0.680851 (-2750 6650);
PAINT MONO (-2750 6650);
DISPLAY INVISIBLE (-2750 6650);
FORCEPROP 0 LAST CDS_SEC 1
J 0
(-2750 6650);
DISPLAY 1.021277 (-2750 6650);
DISPLAY INVISIBLE (-2750 6650);
FORCEPROP 0 LASTPIN (-3050 6550) $PN 1
J 2
(-3060 6560);
DISPLAY 0.680851 (-3060 6560);
PAINT MONO (-3060 6560);
FORCEPROP 0 LASTPIN (-2800 6550) $PN 2
J 0
(-2790 6560);
DISPLAY 0.680851 (-2790 6560);
PAINT MONO (-2790 6560);
FORCEPROP 1 LAST VALUE 33OHM
J 0
(-2750 6550);
DISPLAY 1.234043 (-2750 6550);
PAINT GREEN (-2750 6550);
FORCEPROP 0 LAST PACKAGE 0402
J 0
(-3000 6600);
DISPLAY 1.021277 (-3000 6600);
FORCEPROP 2 LAST SIGNAL_MODEL DEFAULT_RESISTOR_33OHM_2_1
J 0
(-3100 6750);
DISPLAY 1.021277 (-3100 6750);
DISPLAY INVISIBLE (-3100 6750);
FORCEPROP 1 LAST CDS_LMAN_SYM_OUTLINE -50,50,100,-50
J 0
(-2950 6550);
DISPLAY 0.468085 (-2950 6550);
PAINT GREEN (-2950 6550);
DISPLAY INVISIBLE (-2950 6550);
FORCEPROP 2 LAST CDS_LIB passive
J 0
(-2950 6550);
DISPLAY INVISIBLE (-2950 6550);
FORCEPROP 1 LAST CLS_PN G155-133R0-01
J 0
(-3086 6750);
DISPLAY 1.212766 (-3086 6750);
PAINT GREEN (-3086 6750);
DISPLAY INVISIBLE (-3086 6750);
FORCEPROP 1 LAST TOLERANCE 1%
J 0
(-3147 6805);
DISPLAY 1.212766 (-3147 6805);
PAINT GREEN (-3147 6805);
DISPLAY INVISIBLE (-3147 6805);
FORCEPROP 1 LAST PATH I23
J 0
(-3147 6655);
DISPLAY 1.212766 (-3147 6655);
PAINT GREEN (-3147 6655);
DISPLAY INVISIBLE (-3147 6655);
FORCEADD NUT..1
R 2
(-11000 4750);
FORCEPROP 1 LAST $LOCATION MAC_PIN5
J 2
(-11100 4800);
DISPLAY 1.212766 (-11100 4800);
PAINT GREEN (-11100 4800);
FORCEPROP 0 LAST CDS_LOCATION MAC_PIN5
J 2
(-11100 4800);
DISPLAY 1.212766 (-11100 4800);
PAINT GREEN (-11100 4800);
DISPLAY INVISIBLE (-11100 4800);
FORCEPROP 0 LAST $SEC 1
J 0
(-11100 4900);
DISPLAY 0.680851 (-11100 4900);
PAINT MONO (-11100 4900);
DISPLAY INVISIBLE (-11100 4900);
FORCEPROP 0 LAST CDS_SEC 1
J 0
(-11100 4900);
DISPLAY 1.021277 (-11100 4900);
DISPLAY INVISIBLE (-11100 4900);
FORCEPROP 0 LASTPIN (-10850 4750) $PN 1
J 0
(-10840 4760);
DISPLAY 0.680851 (-10840 4760);
PAINT MONO (-10840 4760);
FORCEPROP 1 LAST CLS_PN A200-00029-FB
J 2
(-11150 4700);
DISPLAY 1.212766 (-11150 4700);
PAINT GREEN (-11150 4700);
FORCEPROP 0 LAST PART_NUMBER 0332-0-43-80-18-27-10-0
J 0
(-12200 4650);
DISPLAY 1.021277 (-12200 4650);
FORCEPROP 1 LAST CDS_LMAN_SYM_OUTLINE -50,50,50,-50
J 2
(-11000 4750);
DISPLAY 0.468085 (-11000 4750);
PAINT GREEN (-11000 4750);
DISPLAY INVISIBLE (-11000 4750);
FORCEPROP 2 LAST CDS_LIB mech
J 0
(-11000 4750);
DISPLAY INVISIBLE (-11000 4750);
FORCEPROP 1 LAST PATH I230
J 2
(-10900 4920);
DISPLAY 1.212766 (-10900 4920);
PAINT GREEN (-10900 4920);
DISPLAY INVISIBLE (-10900 4920);
FORCEADD POWERMOS_3P_PCH..1
R 7
(800 1450);
FORCEPROP 1 LAST $LOCATION Q3
J 2
(1200 1400);
DISPLAY 1.212766 (1200 1400);
PAINT GREEN (1200 1400);
FORCEPROP 0 LAST CDS_LOCATION Q3
J 0
(1250 1600);
DISPLAY 1.021277 (1250 1600);
DISPLAY INVISIBLE (1250 1600);
FORCEPROP 0 LAST $SEC 1
J 0
(1250 1600);
DISPLAY 0.680851 (1250 1600);
PAINT MONO (1250 1600);
DISPLAY INVISIBLE (1250 1600);
FORCEPROP 0 LAST CDS_SEC 1
J 0
(1250 1600);
DISPLAY 1.021277 (1250 1600);
DISPLAY INVISIBLE (1250 1600);
FORCEPROP 0 LASTPIN (1000 1750) $PN 3
R 1
J 0
(990 1760);
DISPLAY 0.680851 (990 1760);
PAINT MONO (990 1760);
FORCEPROP 0 LASTPIN (700 1200) $PN 1
R 1
J 2
(690 1190);
DISPLAY 0.680851 (690 1190);
PAINT MONO (690 1190);
FORCEPROP 0 LASTPIN (600 1750) $PN 2
R 1
J 0
(590 1760);
DISPLAY 0.680851 (590 1760);
PAINT MONO (590 1760);
FORCEPROP 0 LAST PART_NUMBER DMP3099L-7
J 0
(1100 1200);
DISPLAY 1.021277 (1100 1200);
FORCEPROP 1 LAST CLS_PN G121-10216-01
J 2
(1850 1300);
DISPLAY 1.212766 (1850 1300);
PAINT GREEN (1850 1300);
FORCEPROP 0 LAST NO_ASSY TRUE
J 0
(1250 1400);
DISPLAY 1.021277 (1250 1400);
DISPLAY BOTH (1250 1400);
FORCEPROP 1 LAST PATH I231
R 1
J 0
(950 1300);
DISPLAY 1.212766 (950 1300);
PAINT GREEN (950 1300);
DISPLAY INVISIBLE (950 1300);
FORCEPROP 2 LAST CDS_LIB discrete
R 1
J 0
(800 1450);
DISPLAY INVISIBLE (800 1450);
FORCEPROP 1 LAST CDS_LMAN_SYM_OUTLINE -200,200,200,-200
R 1
J 0
(800 1450);
DISPLAY 0.468085 (800 1450);
PAINT GREEN (800 1450);
DISPLAY INVISIBLE (800 1450);
FORCEADD POWERMOS_3P_NCH_V1..1
R 2
(450 800);
FORCEPROP 1 LAST $LOCATION Q2
J 2
(150 800);
DISPLAY 1.212766 (150 800);
PAINT GREEN (150 800);
FORCEPROP 0 LAST CDS_LOCATION Q2
J 0
(1000 1050);
DISPLAY 1.021277 (1000 1050);
DISPLAY INVISIBLE (1000 1050);
FORCEPROP 0 LAST $SEC 1
J 0
(1000 1050);
DISPLAY 0.680851 (1000 1050);
PAINT MONO (1000 1050);
DISPLAY INVISIBLE (1000 1050);
FORCEPROP 0 LAST CDS_SEC 1
J 0
(1000 1050);
DISPLAY 1.021277 (1000 1050);
DISPLAY INVISIBLE (1000 1050);
FORCEPROP 0 LASTPIN (200 1000) $PN 3
J 2
(190 1010);
DISPLAY 0.680851 (190 1010);
PAINT MONO (190 1010);
FORCEPROP 0 LASTPIN (700 700) $PN 1
J 0
(710 710);
DISPLAY 0.680851 (710 710);
PAINT MONO (710 710);
FORCEPROP 0 LASTPIN (200 600) $PN 2
J 2
(190 610);
DISPLAY 0.680851 (190 610);
PAINT MONO (190 610);
FORCEPROP 0 LAST PART_NUMBER BSS138
J 2
(1000 950);
DISPLAY 1.021277 (1000 950);
FORCEPROP 0 LAST NO_ASSY TRUE
J 0
(-350 700);
DISPLAY 1.021277 (-350 700);
DISPLAY BOTH (-350 700);
FORCEPROP 1 LAST CLS_PN G121-10200-01
J 2
(1450 850);
DISPLAY 1.212766 (1450 850);
PAINT GREEN (1450 850);
FORCEPROP 1 LAST CDS_LMAN_SYM_OUTLINE -200,200,200,-200
J 2
(450 800);
DISPLAY 0.468085 (450 800);
PAINT GREEN (450 800);
DISPLAY INVISIBLE (450 800);
FORCEPROP 2 LAST CDS_LIB discrete
J 2
(450 800);
DISPLAY INVISIBLE (450 800);
FORCEPROP 1 LAST PATH I232
J 2
(809 1234);
DISPLAY 1.212766 (809 1234);
PAINT GREEN (809 1234);
DISPLAY INVISIBLE (809 1234);
FORCEPROP 2 LASTPIN (200 1000) SIG_NAME UN$527$POWERMOS3PNCHV1$I232$D
J 0
(210 1010);
DISPLAY 0.659574 (210 1010);
PAINT MONO (210 1010);
DISPLAY INVISIBLE (210 1010);
FORCEADD RESISTOR..2
(100 1400);
FORCEPROP 1 LAST $LOCATION R44
J 0
(150 1250);
DISPLAY 1.212766 (150 1250);
PAINT GREEN (150 1250);
FORCEPROP 0 LAST CDS_LOCATION R44
J 0
(150 1550);
DISPLAY 1.021277 (150 1550);
DISPLAY INVISIBLE (150 1550);
FORCEPROP 0 LAST $SEC 1
J 0
(150 1550);
DISPLAY 0.680851 (150 1550);
PAINT MONO (150 1550);
DISPLAY INVISIBLE (150 1550);
FORCEPROP 0 LAST CDS_SEC 1
J 0
(150 1550);
DISPLAY 1.021277 (150 1550);
DISPLAY INVISIBLE (150 1550);
FORCEPROP 0 LASTPIN (100 1500) $PN 1
R 1
J 0
(90 1510);
DISPLAY 0.680851 (90 1510);
PAINT MONO (90 1510);
FORCEPROP 0 LASTPIN (100 1250) $PN 2
R 1
J 2
(90 1240);
DISPLAY 0.680851 (90 1240);
PAINT MONO (90 1240);
FORCEPROP 0 LAST NO_ASSY TRUE
J 0
(150 1200);
DISPLAY 1.021277 (150 1200);
DISPLAY BOTH (150 1200);
FORCEPROP 0 LAST PACKAGE 0402
J 0
(150 1350);
DISPLAY 1.021277 (150 1350);
FORCEPROP 1 LAST VALUE 4.7KOHM
J 0
(150 1450);
DISPLAY 1.212766 (150 1450);
PAINT GREEN (150 1450);
FORCEPROP 1 LAST CLS_PN G155-14701-01
J 0
(-36 1600);
DISPLAY 1.212766 (-36 1600);
PAINT GREEN (-36 1600);
DISPLAY INVISIBLE (-36 1600);
FORCEPROP 1 LAST CDS_LMAN_SYM_OUTLINE -50,50,50,-100
J 0
(100 1400);
DISPLAY 0.468085 (100 1400);
PAINT GREEN (100 1400);
DISPLAY INVISIBLE (100 1400);
FORCEPROP 2 LAST CDS_LIB passive
J 0
(100 1400);
DISPLAY INVISIBLE (100 1400);
FORCEPROP 1 LAST TOLERANCE 1%
J 0
(-97 1655);
DISPLAY 1.212766 (-97 1655);
PAINT GREEN (-97 1655);
DISPLAY INVISIBLE (-97 1655);
FORCEPROP 1 LAST PATH I233
J 0
(-97 1505);
DISPLAY 1.212766 (-97 1505);
PAINT GREEN (-97 1505);
DISPLAY INVISIBLE (-97 1505);
FORCEADD VCC..1
(50 2150);
FORCEPROP 3 LASTPIN (100 2100) SIG_NAME XP5R0V_MAC\g
J 0
(110 2110);
DISPLAY 0.659574 (110 2110);
PAINT MONO (110 2110);
DISPLAY INVISIBLE (110 2110);
FORCEPROP 1 LAST HDL_POWER XP5R0V_MAC
J 1
(100 2200);
DISPLAY 0.808511 (100 2200);
PAINT GREEN (100 2200);
FORCEPROP 0 LAST VOLTAGE 5
J 1
(100 2250);
DISPLAY 1.021277 (100 2250);
DISPLAY BOTH (100 2250);
FORCEPROP 2 LAST CDS_LIB cls
J 0
(50 2150);
DISPLAY INVISIBLE (50 2150);
FORCEPROP 1 LAST CDS_LMAN_SYM_OUTLINE -250,250,250,-250
J 0
(50 2150);
DISPLAY 0.468085 (50 2150);
PAINT GREEN (50 2150);
DISPLAY INVISIBLE (50 2150);
FORCEPROP 1 LAST BODY_TYPE PLUMBING
J 0
(5 2107);
DISPLAY 0.340426 (5 2107);
PAINT GREEN (5 2107);
DISPLAY INVISIBLE (5 2107);
FORCEPROP 1 LAST PATH I234
J 0
(85 2240);
DISPLAY 0.808511 (85 2240);
PAINT GREEN (85 2240);
DISPLAY INVISIBLE (85 2240);
FORCEADD VCC..1
(2100 2150);
FORCEPROP 3 LASTPIN (2150 2100) SIG_NAME XP5R0V_MAC_USB\g
J 0
(2160 2110);
DISPLAY 0.659574 (2160 2110);
PAINT MONO (2160 2110);
DISPLAY INVISIBLE (2160 2110);
FORCEPROP 0 LAST VOLTAGE 5V
J 0
(1900 2250);
DISPLAY BOTH (1900 2250);
FORCEPROP 1 LAST HDL_POWER XP5R0V_MAC_USB
J 1
(2155 2205);
DISPLAY 0.808511 (2155 2205);
PAINT GREEN (2155 2205);
FORCEPROP 1 LAST CDS_LMAN_SYM_OUTLINE -250,250,250,-250
J 0
(2100 2150);
DISPLAY 0.468085 (2100 2150);
PAINT GREEN (2100 2150);
DISPLAY INVISIBLE (2100 2150);
FORCEPROP 2 LAST CDS_LIB cls
J 0
(2100 2150);
DISPLAY INVISIBLE (2100 2150);
FORCEPROP 1 LAST BODY_TYPE PLUMBING
J 0
(2055 2107);
DISPLAY 0.340426 (2055 2107);
PAINT GREEN (2055 2107);
DISPLAY INVISIBLE (2055 2107);
FORCEPROP 1 LAST PATH I235
J 0
(2135 2240);
DISPLAY 0.808511 (2135 2240);
PAINT GREEN (2135 2240);
DISPLAY INVISIBLE (2135 2240);
FORCEADD OFFPAGE_OUT..1
(-600 3900);
FORCEPROP 2 LAST $XR0 21K15< 
J 0
(-545 3900);
DISPLAY 0.638298 (-545 3900);
PAINT MONO (-545 3900);
FORCEPROP 2 LAST CDS_LIB cls
J 2
(-600 3900);
DISPLAY INVISIBLE (-600 3900);
FORCEPROP 1 LAST CDS_LMAN_SYM_OUTLINE -50,50,50,-50
J 0
(-600 3900);
DISPLAY 0.468085 (-600 3900);
PAINT GREEN (-600 3900);
DISPLAY INVISIBLE (-600 3900);
FORCEPROP 1 LAST BODY_TYPE COMMENT
J 0
(-590 4035);
DISPLAY 0.808511 (-590 4035);
PAINT GREEN (-590 4035);
DISPLAY INVISIBLE (-590 4035);
FORCEPROP 1 LAST OFFPAGE TRUE
J 0
(-590 3955);
DISPLAY 0.808511 (-590 3955);
PAINT GREEN (-590 3955);
DISPLAY INVISIBLE (-590 3955);
FORCEPROP 2 LAST PATH I236
J 0
(-550 4000);
DISPLAY 1.021277 (-550 4000);
DISPLAY INVISIBLE (-550 4000);
FORCEADD OFFPAGE_IN..2
(1850 700);
FORCEPROP 2 LAST $XR0 21G13> 
J 0
(1905 700);
DISPLAY 0.638298 (1905 700);
PAINT MONO (1905 700);
FORCEPROP 2 LAST CDS_LIB cls
J 0
(1850 700);
DISPLAY INVISIBLE (1850 700);
FORCEPROP 1 LAST CDS_LMAN_SYM_OUTLINE -50,50,50,-50
J 0
(1850 700);
DISPLAY 0.468085 (1850 700);
PAINT GREEN (1850 700);
DISPLAY INVISIBLE (1850 700);
FORCEPROP 1 LAST BODY_TYPE COMMENT
J 0
(1860 835);
DISPLAY 0.808511 (1860 835);
PAINT GREEN (1860 835);
DISPLAY INVISIBLE (1860 835);
FORCEPROP 1 LAST OFFPAGE TRUE
J 0
(1860 755);
DISPLAY 0.808511 (1860 755);
PAINT GREEN (1860 755);
DISPLAY INVISIBLE (1860 755);
FORCEPROP 2 LAST PATH I237
J 0
(1900 800);
DISPLAY 1.021277 (1900 800);
DISPLAY INVISIBLE (1900 800);
FORCEADD GND_SG..1
(50 500);
FORCEPROP 3 LASTPIN (100 550) SIG_NAME SG\g
J 0
(110 560);
DISPLAY 0.659574 (110 560);
PAINT MONO (110 560);
DISPLAY INVISIBLE (110 560);
FORCEPROP 1 LAST HDL_POWER SG
J 1
(105 405);
DISPLAY 0.808511 (105 405);
PAINT GREEN (105 405);
FORCEPROP 1 LAST CDS_LMAN_SYM_OUTLINE 0,0,100,-50
J 0
(50 500);
DISPLAY 0.468085 (50 500);
PAINT GREEN (50 500);
DISPLAY INVISIBLE (50 500);
FORCEPROP 2 LAST CDS_LIB cls
J 0
(50 500);
DISPLAY INVISIBLE (50 500);
FORCEPROP 1 LAST BODY_TYPE PLUMBING
J 0
(65 485);
DISPLAY 0.808511 (65 485);
PAINT GREEN (65 485);
DISPLAY INVISIBLE (65 485);
FORCEPROP 1 LAST PATH I238
J 0
(85 500);
DISPLAY 0.808511 (85 500);
PAINT GREEN (85 500);
DISPLAY INVISIBLE (85 500);
FORCEADD OFFPAGE_OUT..1
(-800 6550);
FORCEPROP 2 LAST $XR0 11E5< 
J 0
(-745 6550);
DISPLAY 0.638298 (-745 6550);
PAINT MONO (-745 6550);
FORCEPROP 1 LAST OFFPAGE TRUE
J 0
(-790 6605);
DISPLAY 0.808511 (-790 6605);
PAINT GREEN (-790 6605);
DISPLAY INVISIBLE (-790 6605);
FORCEPROP 1 LAST BODY_TYPE COMMENT
J 0
(-790 6685);
DISPLAY 0.808511 (-790 6685);
PAINT GREEN (-790 6685);
DISPLAY INVISIBLE (-790 6685);
FORCEPROP 2 LAST PATH I24
J 0
(-700 6600);
DISPLAY 1.021277 (-700 6600);
DISPLAY INVISIBLE (-700 6600);
FORCEPROP 1 LAST CDS_LMAN_SYM_OUTLINE -50,50,50,-50
J 0
(-800 6550);
DISPLAY 0.468085 (-800 6550);
PAINT GREEN (-800 6550);
DISPLAY INVISIBLE (-800 6550);
FORCEPROP 2 LAST CDS_LIB cls
J 2
(-800 6550);
DISPLAY INVISIBLE (-800 6550);
FORCEADD RESISTOR..1
(-9100 2200);
FORCEPROP 1 LAST $LOCATION R81
J 2
(-9300 2200);
DISPLAY 1.212766 (-9300 2200);
PAINT GREEN (-9300 2200);
FORCEPROP 0 LAST CDS_LOCATION R81
J 0
(-8900 2300);
DISPLAY 1.021277 (-8900 2300);
DISPLAY INVISIBLE (-8900 2300);
FORCEPROP 0 LAST $SEC 1
J 0
(-8900 2300);
DISPLAY 0.680851 (-8900 2300);
PAINT MONO (-8900 2300);
DISPLAY INVISIBLE (-8900 2300);
FORCEPROP 0 LAST CDS_SEC 1
J 0
(-8900 2300);
DISPLAY 1.021277 (-8900 2300);
DISPLAY INVISIBLE (-8900 2300);
FORCEPROP 0 LASTPIN (-9200 2200) $PN 1
J 2
(-9210 2210);
DISPLAY 0.680851 (-9210 2210);
PAINT MONO (-9210 2210);
FORCEPROP 0 LASTPIN (-8950 2200) $PN 2
J 0
(-8940 2210);
DISPLAY 0.680851 (-8940 2210);
PAINT MONO (-8940 2210);
FORCEPROP 0 LAST PACKAGE 0402
J 0
(-9150 2250);
DISPLAY 1.021277 (-9150 2250);
FORCEPROP 1 LAST VALUE 33OHM
J 0
(-8900 2200);
DISPLAY 1.234043 (-8900 2200);
PAINT GREEN (-8900 2200);
FORCEPROP 2 LAST CDS_LIB passive
J 0
(-9100 2200);
DISPLAY INVISIBLE (-9100 2200);
FORCEPROP 1 LAST CDS_LMAN_SYM_OUTLINE -50,50,100,-50
J 0
(-9100 2200);
DISPLAY 0.468085 (-9100 2200);
PAINT GREEN (-9100 2200);
DISPLAY INVISIBLE (-9100 2200);
FORCEPROP 2 LAST SIGNAL_MODEL DEFAULT_RESISTOR_33OHM_2_1
J 0
(-9250 2400);
DISPLAY 1.021277 (-9250 2400);
DISPLAY INVISIBLE (-9250 2400);
FORCEPROP 1 LAST CLS_PN G155-133R0-01
J 0
(-9236 2400);
DISPLAY 1.212766 (-9236 2400);
PAINT GREEN (-9236 2400);
DISPLAY INVISIBLE (-9236 2400);
FORCEPROP 1 LAST TOLERANCE 1%
J 0
(-9297 2455);
DISPLAY 1.212766 (-9297 2455);
PAINT GREEN (-9297 2455);
DISPLAY INVISIBLE (-9297 2455);
FORCEPROP 1 LAST PATH I240
J 0
(-9297 2305);
DISPLAY 1.212766 (-9297 2305);
PAINT GREEN (-9297 2305);
DISPLAY INVISIBLE (-9297 2305);
FORCEADD RESISTOR..1
(-9100 2100);
FORCEPROP 1 LAST $LOCATION R82
J 2
(-9300 2100);
DISPLAY 1.212766 (-9300 2100);
PAINT GREEN (-9300 2100);
FORCEPROP 0 LAST CDS_LOCATION R82
J 0
(-8900 2200);
DISPLAY 1.021277 (-8900 2200);
DISPLAY INVISIBLE (-8900 2200);
FORCEPROP 0 LAST $SEC 1
J 0
(-8900 2200);
DISPLAY 0.680851 (-8900 2200);
PAINT MONO (-8900 2200);
DISPLAY INVISIBLE (-8900 2200);
FORCEPROP 0 LAST CDS_SEC 1
J 0
(-8900 2200);
DISPLAY 1.021277 (-8900 2200);
DISPLAY INVISIBLE (-8900 2200);
FORCEPROP 0 LASTPIN (-9200 2100) $PN 1
J 2
(-9210 2110);
DISPLAY 0.680851 (-9210 2110);
PAINT MONO (-9210 2110);
FORCEPROP 0 LASTPIN (-8950 2100) $PN 2
J 0
(-8940 2110);
DISPLAY 0.680851 (-8940 2110);
PAINT MONO (-8940 2110);
FORCEPROP 0 LAST PACKAGE 0402
J 0
(-9150 2000);
DISPLAY 1.021277 (-9150 2000);
FORCEPROP 1 LAST VALUE 33OHM
J 0
(-8900 2100);
DISPLAY 1.234043 (-8900 2100);
PAINT GREEN (-8900 2100);
FORCEPROP 2 LAST CDS_LIB passive
J 0
(-9100 2100);
DISPLAY INVISIBLE (-9100 2100);
FORCEPROP 1 LAST CDS_LMAN_SYM_OUTLINE -50,50,100,-50
J 0
(-9100 2100);
DISPLAY 0.468085 (-9100 2100);
PAINT GREEN (-9100 2100);
DISPLAY INVISIBLE (-9100 2100);
FORCEPROP 2 LAST SIGNAL_MODEL DEFAULT_RESISTOR_33OHM_2_1
J 0
(-9250 2300);
DISPLAY 1.021277 (-9250 2300);
DISPLAY INVISIBLE (-9250 2300);
FORCEPROP 1 LAST CLS_PN G155-133R0-01
J 0
(-9236 2300);
DISPLAY 1.212766 (-9236 2300);
PAINT GREEN (-9236 2300);
DISPLAY INVISIBLE (-9236 2300);
FORCEPROP 1 LAST TOLERANCE 1%
J 0
(-9297 2355);
DISPLAY 1.212766 (-9297 2355);
PAINT GREEN (-9297 2355);
DISPLAY INVISIBLE (-9297 2355);
FORCEPROP 1 LAST PATH I241
J 0
(-9297 2205);
DISPLAY 1.212766 (-9297 2205);
PAINT GREEN (-9297 2205);
DISPLAY INVISIBLE (-9297 2205);
FORCEADD OFFPAGE_OUT..1
(-7050 2100);
FORCEPROP 2 LAST $XR0 24E15< 
J 0
(-6995 2100);
DISPLAY 0.638298 (-6995 2100);
PAINT MONO (-6995 2100);
FORCEPROP 2 LAST CDS_LIB cls
J 0
(-7050 2100);
DISPLAY INVISIBLE (-7050 2100);
FORCEPROP 1 LAST CDS_LMAN_SYM_OUTLINE -50,50,50,-50
J 0
(-7050 2100);
DISPLAY 0.468085 (-7050 2100);
PAINT GREEN (-7050 2100);
DISPLAY INVISIBLE (-7050 2100);
FORCEPROP 2 LAST PATH I242
J 0
(-6800 2150);
DISPLAY 1.021277 (-6800 2150);
DISPLAY INVISIBLE (-6800 2150);
FORCEPROP 1 LAST OFFPAGE TRUE
J 0
(-7040 2155);
DISPLAY 0.808511 (-7040 2155);
PAINT GREEN (-7040 2155);
DISPLAY INVISIBLE (-7040 2155);
FORCEPROP 1 LAST BODY_TYPE COMMENT
J 0
(-7040 2235);
DISPLAY 0.808511 (-7040 2235);
PAINT GREEN (-7040 2235);
DISPLAY INVISIBLE (-7040 2235);
FORCEADD OFFPAGE_IN..2
(-7050 2200);
FORCEPROP 2 LAST $XR0 24E15> 
J 0
(-6995 2200);
DISPLAY 0.638298 (-6995 2200);
PAINT MONO (-6995 2200);
FORCEPROP 1 LAST CDS_LMAN_SYM_OUTLINE -50,50,50,-50
J 0
(-7050 2200);
DISPLAY 0.468085 (-7050 2200);
PAINT GREEN (-7050 2200);
DISPLAY INVISIBLE (-7050 2200);
FORCEPROP 2 LAST CDS_LIB cls
J 0
(-7050 2200);
DISPLAY INVISIBLE (-7050 2200);
FORCEPROP 1 LAST BODY_TYPE COMMENT
J 0
(-7040 2335);
DISPLAY 0.808511 (-7040 2335);
PAINT GREEN (-7040 2335);
DISPLAY INVISIBLE (-7040 2335);
FORCEPROP 1 LAST OFFPAGE TRUE
J 0
(-7040 2255);
DISPLAY 0.808511 (-7040 2255);
PAINT GREEN (-7040 2255);
DISPLAY INVISIBLE (-7040 2255);
FORCEPROP 2 LAST PATH I243
J 0
(-6800 2250);
DISPLAY 1.021277 (-6800 2250);
DISPLAY INVISIBLE (-6800 2250);
FORCEADD FUSE..1
(1650 1850);
FORCEPROP 1 LAST $LOCATION FU3
J 2
(1518 1900);
DISPLAY 1.212766 (1518 1900);
PAINT GREEN (1518 1900);
FORCEPROP 0 LAST CDS_LOCATION FU3
J 0
(1450 2050);
DISPLAY 1.021277 (1450 2050);
DISPLAY INVISIBLE (1450 2050);
FORCEPROP 0 LAST $SEC 1
J 0
(1450 2050);
DISPLAY 0.680851 (1450 2050);
PAINT MONO (1450 2050);
DISPLAY INVISIBLE (1450 2050);
FORCEPROP 0 LAST CDS_SEC 1
J 0
(1450 2050);
DISPLAY 1.021277 (1450 2050);
DISPLAY INVISIBLE (1450 2050);
FORCEPROP 0 LASTPIN (1500 1850) $PN 1
J 2
(1490 1860);
DISPLAY 0.680851 (1490 1860);
PAINT MONO (1490 1860);
FORCEPROP 0 LASTPIN (1850 1850) $PN 2
J 0
(1860 1860);
DISPLAY 0.680851 (1860 1860);
PAINT MONO (1860 1860);
FORCEPROP 0 LAST NO_ASSY TRUE
J 0
(1450 2000);
DISPLAY 1.021277 (1450 2000);
DISPLAY BOTH (1450 2000);
FORCEPROP 1 LAST VALUE 1A
J 0
(1850 1900);
DISPLAY 1.212766 (1850 1900);
PAINT GREEN (1850 1900);
FORCEPROP 0 LAST PART_NUMBER 0438001.WR
J 0
(1500 1750);
DISPLAY 1.021277 (1500 1750);
FORCEPROP 1 LAST CLS_PN G280-10049-01
J 0
(1800 1950);
DISPLAY 1.212766 (1800 1950);
PAINT GREEN (1800 1950);
DISPLAY INVISIBLE (1800 1950);
FORCEPROP 2 LAST CDS_LIB passive
J 0
(1650 1850);
DISPLAY INVISIBLE (1650 1850);
FORCEPROP 1 LAST CDS_LMAN_SYM_OUTLINE -50,50,100,-50
J 0
(1650 1850);
DISPLAY 0.468085 (1650 1850);
PAINT GREEN (1650 1850);
DISPLAY INVISIBLE (1650 1850);
FORCEPROP 1 LAST PATH I244
J 2
(1550 1950);
DISPLAY 1.212766 (1550 1950);
PAINT GREEN (1550 1950);
DISPLAY INVISIBLE (1550 1950);
FORCEPROP 2 LASTPIN (1500 1850) SIG_NAME UN$527$FUSE$I244$1
J 0
(1510 1860);
DISPLAY 0.659574 (1510 1860);
PAINT MONO (1510 1860);
DISPLAY INVISIBLE (1510 1860);
FORCEADD RESISTOR..1
(750 1850);
FORCEPROP 1 LAST $LOCATION R357
J 2
(650 1900);
DISPLAY 1.212766 (650 1900);
PAINT GREEN (650 1900);
FORCEPROP 0 LAST CDS_LOCATION R357
J 0
(550 2050);
DISPLAY 1.021277 (550 2050);
DISPLAY INVISIBLE (550 2050);
FORCEPROP 0 LAST $SEC 1
J 0
(550 2050);
DISPLAY 0.680851 (550 2050);
PAINT MONO (550 2050);
DISPLAY INVISIBLE (550 2050);
FORCEPROP 0 LAST CDS_SEC 1
J 0
(550 2050);
DISPLAY 1.021277 (550 2050);
DISPLAY INVISIBLE (550 2050);
FORCEPROP 0 LASTPIN (650 1850) $PN 1
J 2
(640 1860);
DISPLAY 0.680851 (640 1860);
PAINT MONO (640 1860);
FORCEPROP 0 LASTPIN (900 1850) $PN 2
J 0
(910 1860);
DISPLAY 0.680851 (910 1860);
PAINT MONO (910 1860);
FORCEPROP 1 LAST VALUE 0OHM
J 0
(950 1900);
DISPLAY 1.234043 (950 1900);
PAINT GREEN (950 1900);
FORCEPROP 0 LAST PACKAGE 0805
J 0
(700 1900);
DISPLAY 1.021277 (700 1900);
FORCEPROP 0 LAST NO_ASSY TRUE
J 0
(550 2000);
DISPLAY 1.021277 (550 2000);
DISPLAY BOTH (550 2000);
FORCEPROP 1 LAST PATH I245
J 0
(553 1955);
DISPLAY 1.212766 (553 1955);
PAINT GREEN (553 1955);
DISPLAY INVISIBLE (553 1955);
FORCEPROP 1 LAST TOLERANCE -
J 0
(553 2105);
DISPLAY 1.212766 (553 2105);
PAINT GREEN (553 2105);
DISPLAY INVISIBLE (553 2105);
FORCEPROP 1 LAST CLS_PN G157-100R0-J0
J 0
(614 2050);
DISPLAY 1.212766 (614 2050);
PAINT GREEN (614 2050);
DISPLAY INVISIBLE (614 2050);
FORCEPROP 1 LAST CDS_LMAN_SYM_OUTLINE -50,50,100,-50
J 0
(750 1850);
DISPLAY 0.468085 (750 1850);
PAINT GREEN (750 1850);
DISPLAY INVISIBLE (750 1850);
FORCEPROP 2 LAST CDS_LIB passive
J 0
(750 1850);
DISPLAY INVISIBLE (750 1850);
FORCEADD OFFPAGE_OUT..1
(-9250 3200);
FORCEPROP 2 LAST $XR0 25D9<> 
J 0
(-9195 3200);
DISPLAY 0.638298 (-9195 3200);
PAINT MONO (-9195 3200);
FORCEPROP 2 LAST CDS_LIB cls
J 0
(-9250 3200);
DISPLAY INVISIBLE (-9250 3200);
FORCEPROP 1 LAST CDS_LMAN_SYM_OUTLINE -50,50,50,-50
J 0
(-9250 3200);
DISPLAY 0.468085 (-9250 3200);
PAINT GREEN (-9250 3200);
DISPLAY INVISIBLE (-9250 3200);
FORCEPROP 2 LAST PATH I246
J 0
(-9200 3300);
DISPLAY 1.021277 (-9200 3300);
DISPLAY INVISIBLE (-9200 3300);
FORCEPROP 1 LAST BODY_TYPE COMMENT
J 0
(-9240 3335);
DISPLAY 0.808511 (-9240 3335);
PAINT GREEN (-9240 3335);
DISPLAY INVISIBLE (-9240 3335);
FORCEPROP 1 LAST OFFPAGE TRUE
J 0
(-9240 3255);
DISPLAY 0.808511 (-9240 3255);
PAINT GREEN (-9240 3255);
DISPLAY INVISIBLE (-9240 3255);
FORCEADD OFFPAGE_OUT..1
(-3400 6450);
FORCEPROP 2 LAST $XR0 25D9<> 
J 0
(-3345 6450);
DISPLAY 0.638298 (-3345 6450);
PAINT MONO (-3345 6450);
FORCEPROP 1 LAST BODY_TYPE COMMENT
J 0
(-3390 6585);
DISPLAY 0.808511 (-3390 6585);
PAINT GREEN (-3390 6585);
DISPLAY INVISIBLE (-3390 6585);
FORCEPROP 1 LAST OFFPAGE TRUE
J 0
(-3390 6505);
DISPLAY 0.808511 (-3390 6505);
PAINT GREEN (-3390 6505);
DISPLAY INVISIBLE (-3390 6505);
FORCEPROP 1 LAST CDS_LMAN_SYM_OUTLINE -50,50,50,-50
J 0
(-3400 6450);
DISPLAY 0.468085 (-3400 6450);
PAINT GREEN (-3400 6450);
DISPLAY INVISIBLE (-3400 6450);
FORCEPROP 2 LAST PATH I247
J 0
(-3350 6550);
DISPLAY 1.021277 (-3350 6550);
DISPLAY INVISIBLE (-3350 6550);
FORCEPROP 2 LAST CDS_LIB cls
J 0
(-3400 6450);
DISPLAY INVISIBLE (-3400 6450);
FORCEADD OFFPAGE_IN..1
(-8900 7150);
FORCEPROP 2 LAST $XR0 13F12> 
J 0
(-9114 7150);
DISPLAY 0.638298 (-9114 7150);
PAINT MONO (-9114 7150);
FORCEPROP 1 LAST BODY_TYPE COMMENT
J 0
(-8890 7285);
DISPLAY 0.808511 (-8890 7285);
PAINT GREEN (-8890 7285);
DISPLAY INVISIBLE (-8890 7285);
FORCEPROP 1 LAST CDS_LMAN_SYM_OUTLINE -50,50,50,-50
J 0
(-8900 7150);
DISPLAY 0.468085 (-8900 7150);
PAINT GREEN (-8900 7150);
DISPLAY INVISIBLE (-8900 7150);
FORCEPROP 2 LAST CDS_LIB cls
J 0
(-8900 7150);
DISPLAY INVISIBLE (-8900 7150);
FORCEPROP 1 LAST OFFPAGE TRUE
J 0
(-8890 7205);
DISPLAY 0.808511 (-8890 7205);
PAINT GREEN (-8890 7205);
DISPLAY INVISIBLE (-8890 7205);
FORCEPROP 2 LAST PATH I25
J 0
(-9050 7200);
DISPLAY 1.021277 (-9050 7200);
DISPLAY INVISIBLE (-9050 7200);
FORCEADD OFFPAGE_IN..1
(-8900 7350);
FORCEPROP 2 LAST $XR0 13F12> 
J 0
(-9114 7350);
DISPLAY 0.638298 (-9114 7350);
PAINT MONO (-9114 7350);
FORCEPROP 2 LAST CDS_LIB cls
J 0
(-8900 7350);
DISPLAY INVISIBLE (-8900 7350);
FORCEPROP 1 LAST CDS_LMAN_SYM_OUTLINE -50,50,50,-50
J 0
(-8900 7350);
DISPLAY 0.468085 (-8900 7350);
PAINT GREEN (-8900 7350);
DISPLAY INVISIBLE (-8900 7350);
FORCEPROP 1 LAST BODY_TYPE COMMENT
J 0
(-8890 7485);
DISPLAY 0.808511 (-8890 7485);
PAINT GREEN (-8890 7485);
DISPLAY INVISIBLE (-8890 7485);
FORCEPROP 1 LAST OFFPAGE TRUE
J 0
(-8890 7405);
DISPLAY 0.808511 (-8890 7405);
PAINT GREEN (-8890 7405);
DISPLAY INVISIBLE (-8890 7405);
FORCEPROP 2 LAST PATH I26
J 0
(-9050 7400);
DISPLAY 1.021277 (-9050 7400);
DISPLAY INVISIBLE (-9050 7400);
FORCEADD OFFPAGE_IN..1
(-8900 7450);
FORCEPROP 2 LAST $XR0 13F12> 
J 0
(-9114 7450);
DISPLAY 0.638298 (-9114 7450);
PAINT MONO (-9114 7450);
FORCEPROP 2 LAST CDS_LIB cls
J 0
(-8900 7450);
DISPLAY INVISIBLE (-8900 7450);
FORCEPROP 1 LAST CDS_LMAN_SYM_OUTLINE -50,50,50,-50
J 0
(-8900 7450);
DISPLAY 0.468085 (-8900 7450);
PAINT GREEN (-8900 7450);
DISPLAY INVISIBLE (-8900 7450);
FORCEPROP 1 LAST BODY_TYPE COMMENT
J 0
(-8890 7585);
DISPLAY 0.808511 (-8890 7585);
PAINT GREEN (-8890 7585);
DISPLAY INVISIBLE (-8890 7585);
FORCEPROP 1 LAST OFFPAGE TRUE
J 0
(-8890 7505);
DISPLAY 0.808511 (-8890 7505);
PAINT GREEN (-8890 7505);
DISPLAY INVISIBLE (-8890 7505);
FORCEPROP 2 LAST PATH I27
J 0
(-9050 7500);
DISPLAY 1.021277 (-9050 7500);
DISPLAY INVISIBLE (-9050 7500);
FORCEADD OFFPAGE_IN..1
(-8900 7250);
FORCEPROP 2 LAST $XR0 13F12> 
J 0
(-9114 7250);
DISPLAY 0.638298 (-9114 7250);
PAINT MONO (-9114 7250);
FORCEPROP 1 LAST BODY_TYPE COMMENT
J 0
(-8890 7385);
DISPLAY 0.808511 (-8890 7385);
PAINT GREEN (-8890 7385);
DISPLAY INVISIBLE (-8890 7385);
FORCEPROP 1 LAST CDS_LMAN_SYM_OUTLINE -50,50,50,-50
J 0
(-8900 7250);
DISPLAY 0.468085 (-8900 7250);
PAINT GREEN (-8900 7250);
DISPLAY INVISIBLE (-8900 7250);
FORCEPROP 2 LAST CDS_LIB cls
J 0
(-8900 7250);
DISPLAY INVISIBLE (-8900 7250);
FORCEPROP 1 LAST OFFPAGE TRUE
J 0
(-8890 7305);
DISPLAY 0.808511 (-8890 7305);
PAINT GREEN (-8890 7305);
DISPLAY INVISIBLE (-8890 7305);
FORCEPROP 2 LAST PATH I28
J 0
(-9050 7300);
DISPLAY 1.021277 (-9050 7300);
DISPLAY INVISIBLE (-9050 7300);
FORCEADD RESISTOR..1
(-7100 7150);
FORCEPROP 1 LAST $LOCATION R86
J 2
(-7250 7150);
DISPLAY 1.212766 (-7250 7150);
PAINT GREEN (-7250 7150);
FORCEPROP 0 LAST CDS_LOCATION R86
J 0
(-6850 7250);
DISPLAY 1.021277 (-6850 7250);
DISPLAY INVISIBLE (-6850 7250);
FORCEPROP 0 LAST $SEC 1
J 0
(-6850 7250);
DISPLAY 0.680851 (-6850 7250);
PAINT MONO (-6850 7250);
DISPLAY INVISIBLE (-6850 7250);
FORCEPROP 0 LAST CDS_SEC 1
J 0
(-6850 7250);
DISPLAY 1.021277 (-6850 7250);
DISPLAY INVISIBLE (-6850 7250);
FORCEPROP 0 LASTPIN (-7200 7150) $PN 1
J 2
(-7210 7160);
DISPLAY 0.680851 (-7210 7160);
PAINT MONO (-7210 7160);
FORCEPROP 0 LASTPIN (-6950 7150) $PN 2
J 0
(-6940 7160);
DISPLAY 0.680851 (-6940 7160);
PAINT MONO (-6940 7160);
FORCEPROP 1 LAST VALUE 0OHM
J 0
(-6850 7150);
DISPLAY 1.212766 (-6850 7150);
PAINT GREEN (-6850 7150);
FORCEPROP 0 LAST PACKAGE 0402
J 0
(-7150 7150);
DISPLAY 0.808511 (-7150 7150);
FORCEPROP 1 LAST CLS_PN G155-100R0-J0
J 0
(-7236 7350);
DISPLAY 1.212766 (-7236 7350);
PAINT GREEN (-7236 7350);
DISPLAY INVISIBLE (-7236 7350);
FORCEPROP 1 LAST CDS_LMAN_SYM_OUTLINE -50,50,100,-50
J 0
(-7100 7150);
DISPLAY 0.468085 (-7100 7150);
PAINT GREEN (-7100 7150);
DISPLAY INVISIBLE (-7100 7150);
FORCEPROP 2 LAST CDS_LIB passive
J 0
(-7100 7150);
DISPLAY INVISIBLE (-7100 7150);
FORCEPROP 1 LAST TOLERANCE -
J 0
(-7297 7405);
DISPLAY 1.212766 (-7297 7405);
PAINT GREEN (-7297 7405);
DISPLAY INVISIBLE (-7297 7405);
FORCEPROP 1 LAST PATH I29
J 0
(-7297 7255);
DISPLAY 1.212766 (-7297 7255);
PAINT GREEN (-7297 7255);
DISPLAY INVISIBLE (-7297 7255);
FORCEADD GND_SG..1
(-11050 -650);
FORCEPROP 3 LASTPIN (-11000 -600) SIG_NAME SG\g
J 0
(-10990 -590);
DISPLAY 0.659574 (-10990 -590);
PAINT MONO (-10990 -590);
DISPLAY INVISIBLE (-10990 -590);
FORCEPROP 1 LAST HDL_POWER SG
J 1
(-10995 -745);
DISPLAY 0.808511 (-10995 -745);
PAINT GREEN (-10995 -745);
FORCEPROP 2 LAST CDS_LIB cls
J 0
(-11050 -650);
DISPLAY INVISIBLE (-11050 -650);
FORCEPROP 1 LAST CDS_LMAN_SYM_OUTLINE 0,0,100,-50
J 0
(-11050 -650);
DISPLAY 0.468085 (-11050 -650);
PAINT GREEN (-11050 -650);
DISPLAY INVISIBLE (-11050 -650);
FORCEPROP 1 LAST BODY_TYPE PLUMBING
J 0
(-11035 -665);
DISPLAY 0.808511 (-11035 -665);
PAINT GREEN (-11035 -665);
DISPLAY INVISIBLE (-11035 -665);
FORCEPROP 1 LAST PATH I3
J 0
(-11015 -650);
DISPLAY 0.808511 (-11015 -650);
PAINT GREEN (-11015 -650);
DISPLAY INVISIBLE (-11015 -650);
FORCEADD RESISTOR..1
(-7100 7250);
FORCEPROP 1 LAST $LOCATION R85
J 2
(-7250 7250);
DISPLAY 1.212766 (-7250 7250);
PAINT GREEN (-7250 7250);
FORCEPROP 0 LAST CDS_LOCATION R85
J 0
(-6850 7350);
DISPLAY 1.021277 (-6850 7350);
DISPLAY INVISIBLE (-6850 7350);
FORCEPROP 0 LAST $SEC 1
J 0
(-6850 7350);
DISPLAY 0.680851 (-6850 7350);
PAINT MONO (-6850 7350);
DISPLAY INVISIBLE (-6850 7350);
FORCEPROP 0 LAST CDS_SEC 1
J 0
(-6850 7350);
DISPLAY 1.021277 (-6850 7350);
DISPLAY INVISIBLE (-6850 7350);
FORCEPROP 0 LASTPIN (-7200 7250) $PN 1
J 2
(-7210 7260);
DISPLAY 0.680851 (-7210 7260);
PAINT MONO (-7210 7260);
FORCEPROP 0 LASTPIN (-6950 7250) $PN 2
J 0
(-6940 7260);
DISPLAY 0.680851 (-6940 7260);
PAINT MONO (-6940 7260);
FORCEPROP 0 LAST PACKAGE 0402
J 0
(-7150 7250);
DISPLAY 0.808511 (-7150 7250);
FORCEPROP 1 LAST VALUE 0OHM
J 0
(-6850 7250);
DISPLAY 1.212766 (-6850 7250);
PAINT GREEN (-6850 7250);
FORCEPROP 2 LAST CDS_LIB passive
J 0
(-7100 7250);
DISPLAY INVISIBLE (-7100 7250);
FORCEPROP 1 LAST CDS_LMAN_SYM_OUTLINE -50,50,100,-50
J 0
(-7100 7250);
DISPLAY 0.468085 (-7100 7250);
PAINT GREEN (-7100 7250);
DISPLAY INVISIBLE (-7100 7250);
FORCEPROP 1 LAST CLS_PN G155-100R0-J0
J 0
(-7236 7450);
DISPLAY 1.212766 (-7236 7450);
PAINT GREEN (-7236 7450);
DISPLAY INVISIBLE (-7236 7450);
FORCEPROP 1 LAST TOLERANCE -
J 0
(-7297 7505);
DISPLAY 1.212766 (-7297 7505);
PAINT GREEN (-7297 7505);
DISPLAY INVISIBLE (-7297 7505);
FORCEPROP 1 LAST PATH I30
J 0
(-7297 7355);
DISPLAY 1.212766 (-7297 7355);
PAINT GREEN (-7297 7355);
DISPLAY INVISIBLE (-7297 7355);
FORCEADD RESISTOR..1
(-7100 7350);
FORCEPROP 1 LAST $LOCATION R84
J 2
(-7250 7350);
DISPLAY 1.212766 (-7250 7350);
PAINT GREEN (-7250 7350);
FORCEPROP 0 LAST CDS_LOCATION R84
J 0
(-6850 7450);
DISPLAY 1.021277 (-6850 7450);
DISPLAY INVISIBLE (-6850 7450);
FORCEPROP 0 LAST $SEC 1
J 0
(-6850 7450);
DISPLAY 0.680851 (-6850 7450);
PAINT MONO (-6850 7450);
DISPLAY INVISIBLE (-6850 7450);
FORCEPROP 0 LAST CDS_SEC 1
J 0
(-6850 7450);
DISPLAY 1.021277 (-6850 7450);
DISPLAY INVISIBLE (-6850 7450);
FORCEPROP 0 LASTPIN (-7200 7350) $PN 1
J 2
(-7210 7360);
DISPLAY 0.680851 (-7210 7360);
PAINT MONO (-7210 7360);
FORCEPROP 0 LASTPIN (-6950 7350) $PN 2
J 0
(-6940 7360);
DISPLAY 0.680851 (-6940 7360);
PAINT MONO (-6940 7360);
FORCEPROP 0 LAST PACKAGE 0402
J 0
(-7150 7350);
DISPLAY 0.808511 (-7150 7350);
FORCEPROP 1 LAST VALUE 0OHM
J 0
(-6850 7350);
DISPLAY 1.212766 (-6850 7350);
PAINT GREEN (-6850 7350);
FORCEPROP 1 LAST CLS_PN G155-100R0-J0
J 0
(-7236 7550);
DISPLAY 1.212766 (-7236 7550);
PAINT GREEN (-7236 7550);
DISPLAY INVISIBLE (-7236 7550);
FORCEPROP 1 LAST CDS_LMAN_SYM_OUTLINE -50,50,100,-50
J 0
(-7100 7350);
DISPLAY 0.468085 (-7100 7350);
PAINT GREEN (-7100 7350);
DISPLAY INVISIBLE (-7100 7350);
FORCEPROP 2 LAST CDS_LIB passive
J 0
(-7100 7350);
DISPLAY INVISIBLE (-7100 7350);
FORCEPROP 1 LAST TOLERANCE -
J 0
(-7297 7605);
DISPLAY 1.212766 (-7297 7605);
PAINT GREEN (-7297 7605);
DISPLAY INVISIBLE (-7297 7605);
FORCEPROP 1 LAST PATH I31
J 0
(-7297 7455);
DISPLAY 1.212766 (-7297 7455);
PAINT GREEN (-7297 7455);
DISPLAY INVISIBLE (-7297 7455);
FORCEADD RESISTOR..1
(-7100 7450);
FORCEPROP 1 LAST $LOCATION R83
J 2
(-7250 7450);
DISPLAY 1.212766 (-7250 7450);
PAINT GREEN (-7250 7450);
FORCEPROP 0 LAST CDS_LOCATION R83
J 0
(-6850 7550);
DISPLAY 1.021277 (-6850 7550);
DISPLAY INVISIBLE (-6850 7550);
FORCEPROP 0 LAST $SEC 1
J 0
(-6850 7550);
DISPLAY 0.680851 (-6850 7550);
PAINT MONO (-6850 7550);
DISPLAY INVISIBLE (-6850 7550);
FORCEPROP 0 LAST CDS_SEC 1
J 0
(-6850 7550);
DISPLAY 1.021277 (-6850 7550);
DISPLAY INVISIBLE (-6850 7550);
FORCEPROP 0 LASTPIN (-7200 7450) $PN 1
J 2
(-7210 7460);
DISPLAY 0.680851 (-7210 7460);
PAINT MONO (-7210 7460);
FORCEPROP 0 LASTPIN (-6950 7450) $PN 2
J 0
(-6940 7460);
DISPLAY 0.680851 (-6940 7460);
PAINT MONO (-6940 7460);
FORCEPROP 0 LAST PACKAGE 0402
J 0
(-7150 7450);
DISPLAY 0.808511 (-7150 7450);
FORCEPROP 1 LAST VALUE 0OHM
J 0
(-6850 7450);
DISPLAY 1.212766 (-6850 7450);
PAINT GREEN (-6850 7450);
FORCEPROP 1 LAST CLS_PN G155-100R0-J0
J 0
(-7236 7650);
DISPLAY 1.212766 (-7236 7650);
PAINT GREEN (-7236 7650);
DISPLAY INVISIBLE (-7236 7650);
FORCEPROP 1 LAST CDS_LMAN_SYM_OUTLINE -50,50,100,-50
J 0
(-7100 7450);
DISPLAY 0.468085 (-7100 7450);
PAINT GREEN (-7100 7450);
DISPLAY INVISIBLE (-7100 7450);
FORCEPROP 2 LAST CDS_LIB passive
J 0
(-7100 7450);
DISPLAY INVISIBLE (-7100 7450);
FORCEPROP 1 LAST TOLERANCE -
J 0
(-7297 7705);
DISPLAY 1.212766 (-7297 7705);
PAINT GREEN (-7297 7705);
DISPLAY INVISIBLE (-7297 7705);
FORCEPROP 1 LAST PATH I32
J 0
(-7297 7555);
DISPLAY 1.212766 (-7297 7555);
PAINT GREEN (-7297 7555);
DISPLAY INVISIBLE (-7297 7555);
FORCEADD RESISTOR..1
(-6050 7050);
FORCEPROP 1 LAST $LOCATION R90
J 2
(-6250 7050);
DISPLAY 1.212766 (-6250 7050);
PAINT GREEN (-6250 7050);
FORCEPROP 0 LAST CDS_LOCATION R90
J 0
(-5800 7150);
DISPLAY 1.021277 (-5800 7150);
DISPLAY INVISIBLE (-5800 7150);
FORCEPROP 0 LAST $SEC 1
J 0
(-5800 7150);
DISPLAY 0.680851 (-5800 7150);
PAINT MONO (-5800 7150);
DISPLAY INVISIBLE (-5800 7150);
FORCEPROP 0 LAST CDS_SEC 1
J 0
(-5800 7150);
DISPLAY 1.021277 (-5800 7150);
DISPLAY INVISIBLE (-5800 7150);
FORCEPROP 0 LASTPIN (-6150 7050) $PN 1
J 2
(-6160 7060);
DISPLAY 0.680851 (-6160 7060);
PAINT MONO (-6160 7060);
FORCEPROP 0 LASTPIN (-5900 7050) $PN 2
J 0
(-5890 7060);
DISPLAY 0.680851 (-5890 7060);
PAINT MONO (-5890 7060);
FORCEPROP 0 LAST NO_ASSY TRUE
J 0
(-6100 6900);
DISPLAY 1.021277 (-6100 6900);
DISPLAY BOTH (-6100 6900);
FORCEPROP 0 LAST PACKAGE 0402
J 0
(-6100 6950);
DISPLAY 1.021277 (-6100 6950);
FORCEPROP 1 LAST VALUE 100OHM
J 0
(-5800 7050);
DISPLAY 1.212766 (-5800 7050);
PAINT GREEN (-5800 7050);
FORCEPROP 1 LAST PATH I33
J 0
(-6247 7155);
DISPLAY 1.212766 (-6247 7155);
PAINT GREEN (-6247 7155);
DISPLAY INVISIBLE (-6247 7155);
FORCEPROP 1 LAST TOLERANCE 1%
J 0
(-6247 7305);
DISPLAY 1.212766 (-6247 7305);
PAINT GREEN (-6247 7305);
DISPLAY INVISIBLE (-6247 7305);
FORCEPROP 2 LAST CDS_LIB passive
J 0
(-6050 7050);
DISPLAY INVISIBLE (-6050 7050);
FORCEPROP 1 LAST CDS_LMAN_SYM_OUTLINE -50,50,100,-50
J 0
(-6050 7050);
DISPLAY 0.468085 (-6050 7050);
PAINT GREEN (-6050 7050);
DISPLAY INVISIBLE (-6050 7050);
FORCEPROP 1 LAST CLS_PN G155-11000-01
J 0
(-6186 7250);
DISPLAY 1.212766 (-6186 7250);
PAINT GREEN (-6186 7250);
DISPLAY INVISIBLE (-6186 7250);
FORCEADD RESISTOR..1
(-6050 7550);
FORCEPROP 1 LAST $LOCATION R89
J 2
(-6200 7550);
DISPLAY 1.212766 (-6200 7550);
PAINT GREEN (-6200 7550);
FORCEPROP 0 LAST CDS_LOCATION R89
J 0
(-5800 7650);
DISPLAY 1.021277 (-5800 7650);
DISPLAY INVISIBLE (-5800 7650);
FORCEPROP 0 LAST $SEC 1
J 0
(-5800 7650);
DISPLAY 0.680851 (-5800 7650);
PAINT MONO (-5800 7650);
DISPLAY INVISIBLE (-5800 7650);
FORCEPROP 0 LAST CDS_SEC 1
J 0
(-5800 7650);
DISPLAY 1.021277 (-5800 7650);
DISPLAY INVISIBLE (-5800 7650);
FORCEPROP 0 LASTPIN (-6150 7550) $PN 1
J 2
(-6160 7560);
DISPLAY 0.680851 (-6160 7560);
PAINT MONO (-6160 7560);
FORCEPROP 0 LASTPIN (-5900 7550) $PN 2
J 0
(-5890 7560);
DISPLAY 0.680851 (-5890 7560);
PAINT MONO (-5890 7560);
FORCEPROP 1 LAST VALUE 100OHM
J 0
(-5800 7550);
DISPLAY 1.212766 (-5800 7550);
PAINT GREEN (-5800 7550);
FORCEPROP 0 LAST PACKAGE 0402
J 0
(-6100 7600);
DISPLAY 1.021277 (-6100 7600);
FORCEPROP 0 LAST NO_ASSY TRUE
J 0
(-6100 7650);
DISPLAY 1.021277 (-6100 7650);
DISPLAY BOTH (-6100 7650);
FORCEPROP 1 LAST CLS_PN G155-11000-01
J 0
(-6186 7750);
DISPLAY 1.212766 (-6186 7750);
PAINT GREEN (-6186 7750);
DISPLAY INVISIBLE (-6186 7750);
FORCEPROP 2 LAST CDS_LIB passive
J 0
(-6050 7550);
DISPLAY INVISIBLE (-6050 7550);
FORCEPROP 1 LAST CDS_LMAN_SYM_OUTLINE -50,50,100,-50
J 0
(-6050 7550);
DISPLAY 0.468085 (-6050 7550);
PAINT GREEN (-6050 7550);
DISPLAY INVISIBLE (-6050 7550);
FORCEPROP 1 LAST TOLERANCE 1%
J 0
(-6247 7805);
DISPLAY 1.212766 (-6247 7805);
PAINT GREEN (-6247 7805);
DISPLAY INVISIBLE (-6247 7805);
FORCEPROP 1 LAST PATH I34
J 0
(-6247 7655);
DISPLAY 1.212766 (-6247 7655);
PAINT GREEN (-6247 7655);
DISPLAY INVISIBLE (-6247 7655);
FORCEADD GND_SG..1
(-10650 2400);
FORCEPROP 3 LASTPIN (-10600 2450) SIG_NAME SG\g
J 0
(-10590 2460);
DISPLAY 0.659574 (-10590 2460);
PAINT MONO (-10590 2460);
DISPLAY INVISIBLE (-10590 2460);
FORCEPROP 1 LAST HDL_POWER SG
J 1
(-10600 2300);
DISPLAY 0.808511 (-10600 2300);
PAINT GREEN (-10600 2300);
FORCEPROP 2 LAST CDS_LIB cls
J 0
(-10650 2400);
DISPLAY INVISIBLE (-10650 2400);
FORCEPROP 1 LAST CDS_LMAN_SYM_OUTLINE 0,0,100,-50
J 0
(-10650 2400);
DISPLAY 0.468085 (-10650 2400);
PAINT GREEN (-10650 2400);
DISPLAY INVISIBLE (-10650 2400);
FORCEPROP 1 LAST BODY_TYPE PLUMBING
J 0
(-10635 2385);
DISPLAY 0.808511 (-10635 2385);
PAINT GREEN (-10635 2385);
DISPLAY INVISIBLE (-10635 2385);
FORCEPROP 1 LAST PATH I37
J 0
(-10615 2400);
DISPLAY 0.808511 (-10615 2400);
PAINT GREEN (-10615 2400);
DISPLAY INVISIBLE (-10615 2400);
FORCEADD CL1001485A..1
R 7
(-10300 -150);
FORCEPROP 1 LAST $LOCATION U9
J 0
(-9750 150);
DISPLAY 1.212766 (-9750 150);
PAINT GREEN (-9750 150);
FORCEPROP 0 LAST CDS_LOCATION U9
J 0
(-9750 250);
DISPLAY 1.021277 (-9750 250);
DISPLAY INVISIBLE (-9750 250);
FORCEPROP 0 LAST $SEC 1
J 0
(-9750 250);
DISPLAY 0.680851 (-9750 250);
PAINT MONO (-9750 250);
DISPLAY INVISIBLE (-9750 250);
FORCEPROP 0 LAST CDS_SEC 1
J 0
(-9750 250);
DISPLAY 1.021277 (-9750 250);
DISPLAY INVISIBLE (-9750 250);
FORCEPROP 0 LASTPIN (-10400 -250) $PN 1
R 1
J 2
(-10410 -260);
DISPLAY 0.680851 (-10410 -260);
PAINT MONO (-10410 -260);
FORCEPROP 0 LASTPIN (-10600 -250) $PN 2
R 1
J 2
(-10610 -260);
DISPLAY 0.680851 (-10610 -260);
PAINT MONO (-10610 -260);
FORCEPROP 0 LASTPIN (-10800 -250) $PN 3
R 1
J 2
(-10810 -260);
DISPLAY 0.680851 (-10810 -260);
PAINT MONO (-10810 -260);
FORCEPROP 0 LASTPIN (-10800 400) $PN 4
R 1
J 0
(-10810 410);
DISPLAY 0.680851 (-10810 410);
PAINT MONO (-10810 410);
FORCEPROP 0 LASTPIN (-10600 400) $PN 5
R 1
J 0
(-10610 410);
DISPLAY 0.680851 (-10610 410);
PAINT MONO (-10610 410);
FORCEPROP 0 LASTPIN (-10400 400) $PN 6
R 1
J 0
(-10410 410);
DISPLAY 0.680851 (-10410 410);
PAINT MONO (-10410 410);
FORCEPROP 0 LAST PART_NUMBER SRV05-4ATCT
J 0
(-10150 50);
DISPLAY 1.021277 (-10150 50);
FORCEPROP 1 LAST CLS_PN G122-00019-01
J 0
(-10150 -50);
DISPLAY 1.212766 (-10150 -50);
PAINT GREEN (-10150 -50);
FORCEPROP 0 LAST NO_ASSY TRUE
J 0
(-10150 -250);
DISPLAY 1.021277 (-10150 -250);
DISPLAY BOTH (-10150 -250);
FORCEPROP 1 LAST CDS_LMAN_SYM_OUTLINE 0,0,450,-600
R 1
J 0
(-10278 -172);
DISPLAY 0.468085 (-10278 -172);
PAINT GREEN (-10278 -172);
DISPLAY INVISIBLE (-10278 -172);
FORCEPROP 2 LAST CDS_LIB other
R 1
J 0
(-10253 -197);
DISPLAY INVISIBLE (-10253 -197);
FORCEPROP 1 LAST PATH I4
R 1
J 0
(-10241 390);
DISPLAY 1.212766 (-10241 390);
PAINT GREEN (-10241 390);
DISPLAY INVISIBLE (-10241 390);
FORCEADD GND_SG..1
(-10250 4200);
FORCEPROP 3 LASTPIN (-10200 4250) SIG_NAME SG\g
J 0
(-10190 4260);
DISPLAY 0.659574 (-10190 4260);
PAINT MONO (-10190 4260);
DISPLAY INVISIBLE (-10190 4260);
FORCEPROP 1 LAST HDL_POWER SG
J 1
(-10200 4100);
DISPLAY 0.808511 (-10200 4100);
PAINT GREEN (-10200 4100);
FORCEPROP 2 LAST CDS_LIB cls
J 0
(-10250 4200);
DISPLAY INVISIBLE (-10250 4200);
FORCEPROP 1 LAST CDS_LMAN_SYM_OUTLINE 0,0,100,-50
J 0
(-10250 4200);
DISPLAY 0.468085 (-10250 4200);
PAINT GREEN (-10250 4200);
DISPLAY INVISIBLE (-10250 4200);
FORCEPROP 0 LAST VOLTAGE 0
J 0
(-10150 4200);
DISPLAY 1.021277 (-10150 4200);
DISPLAY INVISIBLE (-10150 4200);
FORCEPROP 1 LAST BODY_TYPE PLUMBING
J 0
(-10235 4185);
DISPLAY 0.808511 (-10235 4185);
PAINT GREEN (-10235 4185);
DISPLAY INVISIBLE (-10235 4185);
FORCEPROP 1 LAST PATH I45
J 0
(-10215 4200);
DISPLAY 0.808511 (-10215 4200);
PAINT GREEN (-10215 4200);
DISPLAY INVISIBLE (-10215 4200);
FORCEADD VCC..1
(-10450 5000);
FORCEPROP 3 LASTPIN (-10400 4950) SIG_NAME XP5R0V_MAC\g
J 0
(-10390 4960);
DISPLAY 0.659574 (-10390 4960);
PAINT MONO (-10390 4960);
DISPLAY INVISIBLE (-10390 4960);
FORCEPROP 0 LAST VOLTAGE 5
J 1
(-10400 5100);
DISPLAY 1.021277 (-10400 5100);
DISPLAY BOTH (-10400 5100);
FORCEPROP 1 LAST HDL_POWER XP5R0V_MAC
J 1
(-10400 5050);
DISPLAY 0.808511 (-10400 5050);
PAINT GREEN (-10400 5050);
FORCEPROP 1 LAST CDS_LMAN_SYM_OUTLINE -250,250,250,-250
J 0
(-10450 5000);
DISPLAY 0.468085 (-10450 5000);
PAINT GREEN (-10450 5000);
DISPLAY INVISIBLE (-10450 5000);
FORCEPROP 2 LAST CDS_LIB cls
J 0
(-10450 5000);
DISPLAY INVISIBLE (-10450 5000);
FORCEPROP 1 LAST BODY_TYPE PLUMBING
J 0
(-10495 4957);
DISPLAY 0.340426 (-10495 4957);
PAINT GREEN (-10495 4957);
DISPLAY INVISIBLE (-10495 4957);
FORCEPROP 1 LAST PATH I46
J 0
(-10415 5090);
DISPLAY 0.808511 (-10415 5090);
PAINT GREEN (-10415 5090);
DISPLAY INVISIBLE (-10415 5090);
FORCEADD CAPACITOR..1
R 5
(-9250 4550);
FORCEPROP 1 LAST $LOCATION C58
J 2
(-9000 4450);
DISPLAY 1.212766 (-9000 4450);
PAINT GREEN (-9000 4450);
FORCEPROP 0 LAST CDS_LOCATION C58
J 0
(-9150 4650);
DISPLAY 1.021277 (-9150 4650);
DISPLAY INVISIBLE (-9150 4650);
FORCEPROP 0 LAST $SEC 1
J 0
(-9150 4650);
DISPLAY 0.680851 (-9150 4650);
PAINT MONO (-9150 4650);
DISPLAY INVISIBLE (-9150 4650);
FORCEPROP 0 LAST CDS_SEC 1
J 0
(-9150 4650);
DISPLAY 1.021277 (-9150 4650);
DISPLAY INVISIBLE (-9150 4650);
FORCEPROP 0 LASTPIN (-9250 4650) $PN 1
R 1
J 0
(-9260 4660);
DISPLAY 0.680851 (-9260 4660);
PAINT MONO (-9260 4660);
FORCEPROP 0 LASTPIN (-9250 4400) $PN 2
R 1
J 2
(-9260 4390);
DISPLAY 0.680851 (-9260 4390);
PAINT MONO (-9260 4390);
FORCEPROP 0 LAST VOLTAGE 25V
J 0
(-9150 4750);
DISPLAY 1.021277 (-9150 4750);
FORCEPROP 1 LAST VALUE 10UF
J 0
(-9150 4550);
DISPLAY 1.212766 (-9150 4550);
PAINT GREEN (-9150 4550);
FORCEPROP 0 LAST PACKAGE 0805
J 0
(-9150 4650);
DISPLAY 1.021277 (-9150 4650);
FORCEPROP 2 LAST CDS_LIB passive
J 0
(-9250 4550);
DISPLAY INVISIBLE (-9250 4550);
FORCEPROP 1 LAST CDS_LMAN_SYM_OUTLINE 0,50,50,-50
R 3
J 0
(-9250 4550);
DISPLAY 0.468085 (-9250 4550);
PAINT GREEN (-9250 4550);
DISPLAY INVISIBLE (-9250 4550);
FORCEPROP 1 LAST CLS_PN G107-0F106-EM
R 3
J 2
(-9150 4600);
DISPLAY 1.212766 (-9150 4600);
PAINT GREEN (-9150 4600);
DISPLAY INVISIBLE (-9150 4600);
FORCEPROP 1 LAST TOLERANCE 20%
R 3
J 2
(-9150 4650);
DISPLAY 1.212766 (-9150 4650);
PAINT GREEN (-9150 4650);
DISPLAY INVISIBLE (-9150 4650);
FORCEPROP 1 LAST PATH I47
R 3
J 2
(-9150 4600);
DISPLAY 1.212766 (-9150 4600);
PAINT GREEN (-9150 4600);
DISPLAY INVISIBLE (-9150 4600);
FORCEADD CAPACITOR..1
R 3
(-10200 4550);
FORCEPROP 1 LAST $LOCATION C59
J 0
(-10100 4450);
DISPLAY 1.212766 (-10100 4450);
PAINT GREEN (-10100 4450);
FORCEPROP 0 LAST CDS_LOCATION C59
R 1
J 0
(-10100 4650);
DISPLAY 1.021277 (-10100 4650);
DISPLAY INVISIBLE (-10100 4650);
FORCEPROP 0 LAST $SEC 1
R 1
J 0
(-10100 4650);
DISPLAY 0.680851 (-10100 4650);
PAINT MONO (-10100 4650);
DISPLAY INVISIBLE (-10100 4650);
FORCEPROP 0 LAST CDS_SEC 1
R 1
J 0
(-10100 4650);
DISPLAY 1.021277 (-10100 4650);
DISPLAY INVISIBLE (-10100 4650);
FORCEPROP 0 LASTPIN (-10200 4650) $PN 1
R 1
J 0
(-10210 4660);
DISPLAY 0.680851 (-10210 4660);
PAINT MONO (-10210 4660);
FORCEPROP 0 LASTPIN (-10200 4400) $PN 2
R 1
J 2
(-10210 4390);
DISPLAY 0.680851 (-10210 4390);
PAINT MONO (-10210 4390);
FORCEPROP 0 LAST PACKAGE 0402
J 0
(-10100 4650);
DISPLAY 1.021277 (-10100 4650);
FORCEPROP 1 LAST VALUE 0.1UF
J 0
(-10100 4550);
DISPLAY 1.212766 (-10100 4550);
PAINT GREEN (-10100 4550);
FORCEPROP 0 LAST VOLTAGE 25V
J 0
(-10100 4750);
DISPLAY 1.021277 (-10100 4750);
FORCEPROP 1 LAST CDS_LMAN_SYM_OUTLINE 0,50,50,-50
R 1
J 2
(-10200 4550);
DISPLAY 0.468085 (-10200 4550);
PAINT GREEN (-10200 4550);
DISPLAY INVISIBLE (-10200 4550);
FORCEPROP 2 LAST CDS_LIB passive
J 0
(-10200 4550);
DISPLAY INVISIBLE (-10200 4550);
FORCEPROP 1 LAST TOLERANCE 10%
R 1
J 0
(-10300 4650);
DISPLAY 1.212766 (-10300 4650);
PAINT GREEN (-10300 4650);
DISPLAY INVISIBLE (-10300 4650);
FORCEPROP 1 LAST CLS_PN G105-0B104-EK
R 1
J 0
(-10300 4600);
DISPLAY 1.212766 (-10300 4600);
PAINT GREEN (-10300 4600);
DISPLAY INVISIBLE (-10300 4600);
FORCEPROP 1 LAST PATH I48
R 1
J 0
(-10300 4600);
DISPLAY 1.212766 (-10300 4600);
PAINT GREEN (-10300 4600);
DISPLAY INVISIBLE (-10300 4600);
FORCEADD VCC..1
(-4350 7950);
FORCEPROP 3 LASTPIN (-4300 7900) SIG_NAME XP5R0V_MAC_USB\g
J 0
(-4290 7910);
DISPLAY 0.659574 (-4290 7910);
PAINT MONO (-4290 7910);
DISPLAY INVISIBLE (-4290 7910);
FORCEPROP 0 LAST VOLTAGE 5V
J 0
(-4550 8050);
DISPLAY BOTH (-4550 8050);
FORCEPROP 1 LAST HDL_POWER XP5R0V_MAC_USB
J 1
(-4295 8005);
DISPLAY 0.808511 (-4295 8005);
PAINT GREEN (-4295 8005);
FORCEPROP 2 LAST CDS_LIB cls
J 0
(-4350 7950);
DISPLAY INVISIBLE (-4350 7950);
FORCEPROP 1 LAST CDS_LMAN_SYM_OUTLINE -250,250,250,-250
J 0
(-4350 7950);
DISPLAY 0.468085 (-4350 7950);
PAINT GREEN (-4350 7950);
DISPLAY INVISIBLE (-4350 7950);
FORCEPROP 1 LAST BODY_TYPE PLUMBING
J 0
(-4395 7907);
DISPLAY 0.340426 (-4395 7907);
PAINT GREEN (-4395 7907);
DISPLAY INVISIBLE (-4395 7907);
FORCEPROP 1 LAST PATH I49
J 0
(-4315 8040);
DISPLAY 0.808511 (-4315 8040);
PAINT GREEN (-4315 8040);
DISPLAY INVISIBLE (-4315 8040);
FORCEADD GND_SG..1
(-4250 6750);
FORCEPROP 3 LASTPIN (-4200 6800) SIG_NAME SG\g
J 0
(-4190 6810);
DISPLAY 0.659574 (-4190 6810);
PAINT MONO (-4190 6810);
DISPLAY INVISIBLE (-4190 6810);
FORCEPROP 1 LAST HDL_POWER SG
J 1
(-4195 6655);
DISPLAY 0.808511 (-4195 6655);
PAINT GREEN (-4195 6655);
FORCEPROP 2 LAST CDS_LIB cls
J 0
(-4250 6750);
DISPLAY INVISIBLE (-4250 6750);
FORCEPROP 1 LAST CDS_LMAN_SYM_OUTLINE 0,0,100,-50
J 0
(-4250 6750);
DISPLAY 0.468085 (-4250 6750);
PAINT GREEN (-4250 6750);
DISPLAY INVISIBLE (-4250 6750);
FORCEPROP 0 LAST VOLTAGE 0
J 0
(-4150 6750);
DISPLAY 1.021277 (-4150 6750);
DISPLAY INVISIBLE (-4150 6750);
FORCEPROP 1 LAST BODY_TYPE PLUMBING
J 0
(-4235 6735);
DISPLAY 0.808511 (-4235 6735);
PAINT GREEN (-4235 6735);
DISPLAY INVISIBLE (-4235 6735);
FORCEPROP 1 LAST PATH I50
J 0
(-4215 6750);
DISPLAY 0.808511 (-4215 6750);
PAINT GREEN (-4215 6750);
DISPLAY INVISIBLE (-4215 6750);
FORCEADD CAPACITOR..1
R 5
(-4200 7100);
FORCEPROP 1 LAST $LOCATION C64
J 2
(-3950 7000);
DISPLAY 1.212766 (-3950 7000);
PAINT GREEN (-3950 7000);
FORCEPROP 0 LAST CDS_LOCATION C64
J 0
(-4100 7200);
DISPLAY 1.021277 (-4100 7200);
DISPLAY INVISIBLE (-4100 7200);
FORCEPROP 0 LAST $SEC 1
J 0
(-4100 7200);
DISPLAY 0.680851 (-4100 7200);
PAINT MONO (-4100 7200);
DISPLAY INVISIBLE (-4100 7200);
FORCEPROP 0 LAST CDS_SEC 1
J 0
(-4100 7200);
DISPLAY 1.021277 (-4100 7200);
DISPLAY INVISIBLE (-4100 7200);
FORCEPROP 0 LASTPIN (-4200 7200) $PN 1
R 1
J 0
(-4210 7210);
DISPLAY 0.680851 (-4210 7210);
PAINT MONO (-4210 7210);
FORCEPROP 0 LASTPIN (-4200 6950) $PN 2
R 1
J 2
(-4210 6940);
DISPLAY 0.680851 (-4210 6940);
PAINT MONO (-4210 6940);
FORCEPROP 0 LAST VOLTAGE 25V
J 0
(-4100 7200);
DISPLAY 1.021277 (-4100 7200);
FORCEPROP 0 LAST PACKAGE 0805
J 0
(-4100 6900);
DISPLAY 1.021277 (-4100 6900);
FORCEPROP 1 LAST VALUE 10UF
J 0
(-4100 7100);
DISPLAY 1.212766 (-4100 7100);
PAINT GREEN (-4100 7100);
FORCEPROP 2 LAST CDS_LIB passive
J 0
(-4200 7100);
DISPLAY INVISIBLE (-4200 7100);
FORCEPROP 1 LAST CDS_LMAN_SYM_OUTLINE 0,50,50,-50
R 3
J 0
(-4200 7100);
DISPLAY 0.468085 (-4200 7100);
PAINT GREEN (-4200 7100);
DISPLAY INVISIBLE (-4200 7100);
FORCEPROP 1 LAST CLS_PN G107-0F106-EM
R 3
J 2
(-4100 7150);
DISPLAY 1.212766 (-4100 7150);
PAINT GREEN (-4100 7150);
DISPLAY INVISIBLE (-4100 7150);
FORCEPROP 1 LAST TOLERANCE 20%
R 3
J 2
(-4100 7200);
DISPLAY 1.212766 (-4100 7200);
PAINT GREEN (-4100 7200);
DISPLAY INVISIBLE (-4100 7200);
FORCEPROP 1 LAST PATH I51
R 3
J 2
(-4100 7150);
DISPLAY 1.212766 (-4100 7150);
PAINT GREEN (-4100 7150);
DISPLAY INVISIBLE (-4100 7150);
FORCEADD RESISTOR..1
(-8050 2800);
FORCEPROP 1 LAST $LOCATION R95
J 2
(-8250 2800);
DISPLAY 1.212766 (-8250 2800);
PAINT GREEN (-8250 2800);
FORCEPROP 0 LAST CDS_LOCATION R95
J 0
(-7850 2900);
DISPLAY 1.021277 (-7850 2900);
DISPLAY INVISIBLE (-7850 2900);
FORCEPROP 0 LAST $SEC 1
J 0
(-7850 2900);
DISPLAY 0.680851 (-7850 2900);
PAINT MONO (-7850 2900);
DISPLAY INVISIBLE (-7850 2900);
FORCEPROP 0 LAST CDS_SEC 1
J 0
(-7850 2900);
DISPLAY 1.021277 (-7850 2900);
DISPLAY INVISIBLE (-7850 2900);
FORCEPROP 0 LASTPIN (-8150 2800) $PN 1
J 2
(-8160 2810);
DISPLAY 0.680851 (-8160 2810);
PAINT MONO (-8160 2810);
FORCEPROP 0 LASTPIN (-7900 2800) $PN 2
J 0
(-7890 2810);
DISPLAY 0.680851 (-7890 2810);
PAINT MONO (-7890 2810);
FORCEPROP 0 LAST PACKAGE 0402
J 0
(-8100 2850);
DISPLAY 1.021277 (-8100 2850);
FORCEPROP 1 LAST VALUE 33OHM
J 0
(-7850 2800);
DISPLAY 1.234043 (-7850 2800);
PAINT GREEN (-7850 2800);
FORCEPROP 2 LAST CDS_LIB passive
J 0
(-8050 2800);
DISPLAY INVISIBLE (-8050 2800);
FORCEPROP 1 LAST CDS_LMAN_SYM_OUTLINE -50,50,100,-50
J 0
(-8050 2800);
DISPLAY 0.468085 (-8050 2800);
PAINT GREEN (-8050 2800);
DISPLAY INVISIBLE (-8050 2800);
FORCEPROP 2 LAST SIGNAL_MODEL DEFAULT_RESISTOR_33OHM_2_1
J 0
(-8200 3000);
DISPLAY 1.021277 (-8200 3000);
DISPLAY INVISIBLE (-8200 3000);
FORCEPROP 1 LAST CLS_PN G155-133R0-01
J 0
(-8186 3000);
DISPLAY 1.212766 (-8186 3000);
PAINT GREEN (-8186 3000);
DISPLAY INVISIBLE (-8186 3000);
FORCEPROP 1 LAST TOLERANCE 1%
J 0
(-8247 3055);
DISPLAY 1.212766 (-8247 3055);
PAINT GREEN (-8247 3055);
DISPLAY INVISIBLE (-8247 3055);
FORCEPROP 1 LAST PATH I52
J 0
(-8247 2905);
DISPLAY 1.212766 (-8247 2905);
PAINT GREEN (-8247 2905);
DISPLAY INVISIBLE (-8247 2905);
FORCEADD RESISTOR..1
(-8050 3300);
FORCEPROP 1 LAST $LOCATION R93
J 2
(-8250 3300);
DISPLAY 1.212766 (-8250 3300);
PAINT GREEN (-8250 3300);
FORCEPROP 0 LAST CDS_LOCATION R93
J 0
(-7850 3400);
DISPLAY 1.021277 (-7850 3400);
DISPLAY INVISIBLE (-7850 3400);
FORCEPROP 0 LAST $SEC 1
J 0
(-7850 3400);
DISPLAY 0.680851 (-7850 3400);
PAINT MONO (-7850 3400);
DISPLAY INVISIBLE (-7850 3400);
FORCEPROP 0 LAST CDS_SEC 1
J 0
(-7850 3400);
DISPLAY 1.021277 (-7850 3400);
DISPLAY INVISIBLE (-7850 3400);
FORCEPROP 0 LASTPIN (-8150 3300) $PN 1
J 2
(-8160 3310);
DISPLAY 0.680851 (-8160 3310);
PAINT MONO (-8160 3310);
FORCEPROP 0 LASTPIN (-7900 3300) $PN 2
J 0
(-7890 3310);
DISPLAY 0.680851 (-7890 3310);
PAINT MONO (-7890 3310);
FORCEPROP 0 LAST PACKAGE 0402
J 0
(-8100 3350);
DISPLAY 1.021277 (-8100 3350);
FORCEPROP 1 LAST VALUE 33OHM
J 0
(-7850 3300);
DISPLAY 1.234043 (-7850 3300);
PAINT GREEN (-7850 3300);
FORCEPROP 2 LAST SIGNAL_MODEL DEFAULT_RESISTOR_33OHM_2_1
J 0
(-8200 3500);
DISPLAY 1.021277 (-8200 3500);
DISPLAY INVISIBLE (-8200 3500);
FORCEPROP 1 LAST CDS_LMAN_SYM_OUTLINE -50,50,100,-50
J 0
(-8050 3300);
DISPLAY 0.468085 (-8050 3300);
PAINT GREEN (-8050 3300);
DISPLAY INVISIBLE (-8050 3300);
FORCEPROP 2 LAST CDS_LIB passive
J 0
(-8050 3300);
DISPLAY INVISIBLE (-8050 3300);
FORCEPROP 1 LAST CLS_PN G155-133R0-01
J 0
(-8186 3500);
DISPLAY 1.212766 (-8186 3500);
PAINT GREEN (-8186 3500);
DISPLAY INVISIBLE (-8186 3500);
FORCEPROP 1 LAST TOLERANCE 1%
J 0
(-8247 3555);
DISPLAY 1.212766 (-8247 3555);
PAINT GREEN (-8247 3555);
DISPLAY INVISIBLE (-8247 3555);
FORCEPROP 1 LAST PATH I53
J 0
(-8247 3405);
DISPLAY 1.212766 (-8247 3405);
PAINT GREEN (-8247 3405);
DISPLAY INVISIBLE (-8247 3405);
FORCEADD RESISTOR..1
(-8050 3050);
FORCEPROP 1 LAST $LOCATION R94
J 2
(-8250 3050);
DISPLAY 1.212766 (-8250 3050);
PAINT GREEN (-8250 3050);
FORCEPROP 0 LAST CDS_LOCATION R94
J 0
(-7850 3150);
DISPLAY 1.021277 (-7850 3150);
DISPLAY INVISIBLE (-7850 3150);
FORCEPROP 0 LAST $SEC 1
J 0
(-7850 3150);
DISPLAY 0.680851 (-7850 3150);
PAINT MONO (-7850 3150);
DISPLAY INVISIBLE (-7850 3150);
FORCEPROP 0 LAST CDS_SEC 1
J 0
(-7850 3150);
DISPLAY 1.021277 (-7850 3150);
DISPLAY INVISIBLE (-7850 3150);
FORCEPROP 0 LASTPIN (-8150 3050) $PN 1
J 2
(-8160 3060);
DISPLAY 0.680851 (-8160 3060);
PAINT MONO (-8160 3060);
FORCEPROP 0 LASTPIN (-7900 3050) $PN 2
J 0
(-7890 3060);
DISPLAY 0.680851 (-7890 3060);
PAINT MONO (-7890 3060);
FORCEPROP 0 LAST PACKAGE 0402
J 0
(-8100 3100);
DISPLAY 1.021277 (-8100 3100);
FORCEPROP 1 LAST VALUE 33OHM
J 0
(-7850 3050);
DISPLAY 1.234043 (-7850 3050);
PAINT GREEN (-7850 3050);
FORCEPROP 2 LAST SIGNAL_MODEL DEFAULT_RESISTOR_33OHM_2_1
J 0
(-8200 3250);
DISPLAY 1.021277 (-8200 3250);
DISPLAY INVISIBLE (-8200 3250);
FORCEPROP 1 LAST CDS_LMAN_SYM_OUTLINE -50,50,100,-50
J 0
(-8050 3050);
DISPLAY 0.468085 (-8050 3050);
PAINT GREEN (-8050 3050);
DISPLAY INVISIBLE (-8050 3050);
FORCEPROP 2 LAST CDS_LIB passive
J 0
(-8050 3050);
DISPLAY INVISIBLE (-8050 3050);
FORCEPROP 1 LAST CLS_PN G155-133R0-01
J 0
(-8186 3250);
DISPLAY 1.212766 (-8186 3250);
PAINT GREEN (-8186 3250);
DISPLAY INVISIBLE (-8186 3250);
FORCEPROP 1 LAST TOLERANCE 1%
J 0
(-8247 3305);
DISPLAY 1.212766 (-8247 3305);
PAINT GREEN (-8247 3305);
DISPLAY INVISIBLE (-8247 3305);
FORCEPROP 1 LAST PATH I54
J 0
(-8247 3155);
DISPLAY 1.212766 (-8247 3155);
PAINT GREEN (-8247 3155);
DISPLAY INVISIBLE (-8247 3155);
FORCEADD RESISTOR..2
R 3
(-8050 3550);
FORCEPROP 1 LAST $LOCATION R92
J 2
(-8250 3550);
DISPLAY 1.212766 (-8250 3550);
PAINT GREEN (-8250 3550);
FORCEPROP 0 LAST CDS_LOCATION R92
R 1
J 0
(-8250 3650);
DISPLAY 1.021277 (-8250 3650);
DISPLAY INVISIBLE (-8250 3650);
FORCEPROP 0 LAST $SEC 1
R 1
J 0
(-8250 3650);
DISPLAY 0.680851 (-8250 3650);
PAINT MONO (-8250 3650);
DISPLAY INVISIBLE (-8250 3650);
FORCEPROP 0 LAST CDS_SEC 1
R 1
J 0
(-8250 3650);
DISPLAY 1.021277 (-8250 3650);
DISPLAY INVISIBLE (-8250 3650);
FORCEPROP 0 LASTPIN (-8150 3550) $PN 1
J 2
(-8160 3560);
DISPLAY 0.680851 (-8160 3560);
PAINT MONO (-8160 3560);
FORCEPROP 0 LASTPIN (-7900 3550) $PN 2
J 0
(-7890 3560);
DISPLAY 0.680851 (-7890 3560);
PAINT MONO (-7890 3560);
FORCEPROP 0 LAST PACKAGE 0402
J 0
(-8100 3600);
DISPLAY 1.021277 (-8100 3600);
FORCEPROP 1 LAST VALUE 100OHM
J 2
(-7500 3550);
DISPLAY 1.212766 (-7500 3550);
PAINT GREEN (-7500 3550);
FORCEPROP 1 LAST PATH I55
R 1
J 2
(-8155 3747);
DISPLAY 1.212766 (-8155 3747);
PAINT GREEN (-8155 3747);
DISPLAY INVISIBLE (-8155 3747);
FORCEPROP 1 LAST CDS_LMAN_SYM_OUTLINE -50,50,50,-100
R 1
J 2
(-8050 3550);
DISPLAY 0.468085 (-8050 3550);
PAINT GREEN (-8050 3550);
DISPLAY INVISIBLE (-8050 3550);
FORCEPROP 2 LAST CDS_LIB passive
J 0
(-8050 3550);
DISPLAY INVISIBLE (-8050 3550);
FORCEPROP 1 LAST TOLERANCE 1%
R 1
J 2
(-8305 3747);
DISPLAY 1.212766 (-8305 3747);
PAINT GREEN (-8305 3747);
DISPLAY INVISIBLE (-8305 3747);
FORCEPROP 1 LAST CLS_PN G155-11000-01
R 1
J 2
(-8250 3686);
DISPLAY 1.212766 (-8250 3686);
PAINT GREEN (-8250 3686);
DISPLAY INVISIBLE (-8250 3686);
FORCEADD CAPACITOR..1
R 3
(-3700 7100);
FORCEPROP 1 LAST $LOCATION C65
J 0
(-3600 7000);
DISPLAY 1.212766 (-3600 7000);
PAINT GREEN (-3600 7000);
FORCEPROP 0 LAST CDS_LOCATION C65
R 1
J 0
(-3600 7200);
DISPLAY 1.021277 (-3600 7200);
DISPLAY INVISIBLE (-3600 7200);
FORCEPROP 0 LAST $SEC 1
R 1
J 0
(-3600 7200);
DISPLAY 0.680851 (-3600 7200);
PAINT MONO (-3600 7200);
DISPLAY INVISIBLE (-3600 7200);
FORCEPROP 0 LAST CDS_SEC 1
R 1
J 0
(-3600 7200);
DISPLAY 1.021277 (-3600 7200);
DISPLAY INVISIBLE (-3600 7200);
FORCEPROP 0 LASTPIN (-3700 7200) $PN 1
R 1
J 0
(-3710 7210);
DISPLAY 0.680851 (-3710 7210);
PAINT MONO (-3710 7210);
FORCEPROP 0 LASTPIN (-3700 6950) $PN 2
R 1
J 2
(-3710 6940);
DISPLAY 0.680851 (-3710 6940);
PAINT MONO (-3710 6940);
FORCEPROP 1 LAST VALUE 0.1UF
J 0
(-3600 7100);
DISPLAY 1.212766 (-3600 7100);
PAINT GREEN (-3600 7100);
FORCEPROP 0 LAST PACKAGE 0402
J 0
(-3600 6900);
DISPLAY 1.021277 (-3600 6900);
FORCEPROP 0 LAST VOLTAGE 25V
J 0
(-3600 7200);
DISPLAY 1.021277 (-3600 7200);
FORCEPROP 1 LAST CLS_PN G105-0B104-EK
R 1
J 0
(-3800 7150);
DISPLAY 1.212766 (-3800 7150);
PAINT GREEN (-3800 7150);
DISPLAY INVISIBLE (-3800 7150);
FORCEPROP 2 LAST CDS_LIB passive
J 0
(-3700 7100);
DISPLAY INVISIBLE (-3700 7100);
FORCEPROP 1 LAST CDS_LMAN_SYM_OUTLINE 0,50,50,-50
R 1
J 2
(-3700 7100);
DISPLAY 0.468085 (-3700 7100);
PAINT GREEN (-3700 7100);
DISPLAY INVISIBLE (-3700 7100);
FORCEPROP 1 LAST TOLERANCE 10%
R 1
J 0
(-3800 7200);
DISPLAY 1.212766 (-3800 7200);
PAINT GREEN (-3800 7200);
DISPLAY INVISIBLE (-3800 7200);
FORCEPROP 1 LAST PATH I56
R 1
J 0
(-3800 7150);
DISPLAY 1.212766 (-3800 7150);
PAINT GREEN (-3800 7150);
DISPLAY INVISIBLE (-3800 7150);
FORCEADD CAPACITOR..1
R 3
(-3200 7100);
FORCEPROP 1 LAST $LOCATION C66
J 0
(-3100 7000);
DISPLAY 1.212766 (-3100 7000);
PAINT GREEN (-3100 7000);
FORCEPROP 0 LAST CDS_LOCATION C66
R 1
J 0
(-3100 7200);
DISPLAY 1.021277 (-3100 7200);
DISPLAY INVISIBLE (-3100 7200);
FORCEPROP 0 LAST $SEC 1
R 1
J 0
(-3100 7200);
DISPLAY 0.680851 (-3100 7200);
PAINT MONO (-3100 7200);
DISPLAY INVISIBLE (-3100 7200);
FORCEPROP 0 LAST CDS_SEC 1
R 1
J 0
(-3100 7200);
DISPLAY 1.021277 (-3100 7200);
DISPLAY INVISIBLE (-3100 7200);
FORCEPROP 0 LASTPIN (-3200 7200) $PN 1
R 1
J 0
(-3210 7210);
DISPLAY 0.680851 (-3210 7210);
PAINT MONO (-3210 7210);
FORCEPROP 0 LASTPIN (-3200 6950) $PN 2
R 1
J 2
(-3210 6940);
DISPLAY 0.680851 (-3210 6940);
PAINT MONO (-3210 6940);
FORCEPROP 1 LAST VALUE 0.1UF
J 0
(-3100 7100);
DISPLAY 1.212766 (-3100 7100);
PAINT GREEN (-3100 7100);
FORCEPROP 0 LAST VOLTAGE 25V
J 0
(-3100 7200);
DISPLAY 1.021277 (-3100 7200);
FORCEPROP 0 LAST PACKAGE 0402
J 0
(-3100 6900);
DISPLAY 1.021277 (-3100 6900);
FORCEPROP 1 LAST CLS_PN G105-0B104-EK
R 1
J 0
(-3300 7150);
DISPLAY 1.212766 (-3300 7150);
PAINT GREEN (-3300 7150);
DISPLAY INVISIBLE (-3300 7150);
FORCEPROP 2 LAST CDS_LIB passive
J 0
(-3200 7100);
DISPLAY INVISIBLE (-3200 7100);
FORCEPROP 1 LAST CDS_LMAN_SYM_OUTLINE 0,50,50,-50
R 1
J 2
(-3200 7100);
DISPLAY 0.468085 (-3200 7100);
PAINT GREEN (-3200 7100);
DISPLAY INVISIBLE (-3200 7100);
FORCEPROP 1 LAST TOLERANCE 10%
R 1
J 0
(-3300 7200);
DISPLAY 1.212766 (-3300 7200);
PAINT GREEN (-3300 7200);
DISPLAY INVISIBLE (-3300 7200);
FORCEPROP 1 LAST PATH I57
R 1
J 0
(-3300 7150);
DISPLAY 1.212766 (-3300 7150);
PAINT GREEN (-3300 7150);
DISPLAY INVISIBLE (-3300 7150);
FORCEADD OFFPAGE_OUT..1
R 2
(-8900 6650);
FORCEPROP 2 LAST $XR0 13E12< 
J 0
(-9114 6650);
DISPLAY 0.638298 (-9114 6650);
PAINT MONO (-9114 6650);
FORCEPROP 1 LAST BODY_TYPE COMMENT
J 2
(-8910 6785);
DISPLAY 0.808511 (-8910 6785);
PAINT GREEN (-8910 6785);
DISPLAY INVISIBLE (-8910 6785);
FORCEPROP 1 LAST CDS_LMAN_SYM_OUTLINE -50,50,50,-50
J 2
(-8900 6650);
DISPLAY 0.468085 (-8900 6650);
PAINT GREEN (-8900 6650);
DISPLAY INVISIBLE (-8900 6650);
FORCEPROP 2 LAST CDS_LIB cls
J 0
(-8900 6650);
DISPLAY INVISIBLE (-8900 6650);
FORCEPROP 1 LAST OFFPAGE TRUE
J 2
(-8910 6705);
DISPLAY 0.808511 (-8910 6705);
PAINT GREEN (-8910 6705);
DISPLAY INVISIBLE (-8910 6705);
FORCEPROP 2 LAST PATH I6
J 0
(-9050 6700);
DISPLAY 1.021277 (-9050 6700);
DISPLAY INVISIBLE (-9050 6700);
FORCEADD OFFPAGE_IN..2
(-6000 2800);
FORCEPROP 2 LAST $XR0 11G12> 
J 0
(-5945 2800);
DISPLAY 0.638298 (-5945 2800);
PAINT MONO (-5945 2800);
FORCEPROP 1 LAST CDS_LMAN_SYM_OUTLINE -50,50,50,-50
J 0
(-6000 2800);
DISPLAY 0.468085 (-6000 2800);
PAINT GREEN (-6000 2800);
DISPLAY INVISIBLE (-6000 2800);
FORCEPROP 2 LAST CDS_LIB cls
J 0
(-6000 2800);
DISPLAY INVISIBLE (-6000 2800);
FORCEPROP 1 LAST BODY_TYPE COMMENT
J 0
(-5990 2935);
DISPLAY 0.808511 (-5990 2935);
PAINT GREEN (-5990 2935);
DISPLAY INVISIBLE (-5990 2935);
FORCEPROP 1 LAST OFFPAGE TRUE
J 0
(-5990 2855);
DISPLAY 0.808511 (-5990 2855);
PAINT GREEN (-5990 2855);
DISPLAY INVISIBLE (-5990 2855);
FORCEPROP 2 LAST PATH I62
J 0
(-5750 2850);
DISPLAY 1.021277 (-5750 2850);
DISPLAY INVISIBLE (-5750 2850);
FORCEADD OFFPAGE_OUT..1
(-6000 3050);
FORCEPROP 2 LAST $XR0 11G12< 
J 0
(-5945 3050);
DISPLAY 0.638298 (-5945 3050);
PAINT MONO (-5945 3050);
FORCEPROP 2 LAST CDS_LIB cls
J 0
(-6000 3050);
DISPLAY INVISIBLE (-6000 3050);
FORCEPROP 1 LAST CDS_LMAN_SYM_OUTLINE -50,50,50,-50
J 0
(-6000 3050);
DISPLAY 0.468085 (-6000 3050);
PAINT GREEN (-6000 3050);
DISPLAY INVISIBLE (-6000 3050);
FORCEPROP 1 LAST BODY_TYPE COMMENT
J 0
(-5990 3185);
DISPLAY 0.808511 (-5990 3185);
PAINT GREEN (-5990 3185);
DISPLAY INVISIBLE (-5990 3185);
FORCEPROP 1 LAST OFFPAGE TRUE
J 0
(-5990 3105);
DISPLAY 0.808511 (-5990 3105);
PAINT GREEN (-5990 3105);
DISPLAY INVISIBLE (-5990 3105);
FORCEPROP 2 LAST PATH I63
J 0
(-5750 3100);
DISPLAY 1.021277 (-5750 3100);
DISPLAY INVISIBLE (-5750 3100);
FORCEADD OFFPAGE_OUT..1
(-6000 3300);
FORCEPROP 2 LAST $XR0 11E5< 
J 0
(-5945 3300);
DISPLAY 0.638298 (-5945 3300);
PAINT MONO (-5945 3300);
FORCEPROP 1 LAST BODY_TYPE COMMENT
J 0
(-5990 3435);
DISPLAY 0.808511 (-5990 3435);
PAINT GREEN (-5990 3435);
DISPLAY INVISIBLE (-5990 3435);
FORCEPROP 1 LAST CDS_LMAN_SYM_OUTLINE -50,50,50,-50
J 0
(-6000 3300);
DISPLAY 0.468085 (-6000 3300);
PAINT GREEN (-6000 3300);
DISPLAY INVISIBLE (-6000 3300);
FORCEPROP 2 LAST CDS_LIB cls
J 0
(-6000 3300);
DISPLAY INVISIBLE (-6000 3300);
FORCEPROP 1 LAST OFFPAGE TRUE
J 0
(-5990 3355);
DISPLAY 0.808511 (-5990 3355);
PAINT GREEN (-5990 3355);
DISPLAY INVISIBLE (-5990 3355);
FORCEPROP 2 LAST PATH I64
J 0
(-5900 3350);
DISPLAY 1.021277 (-5900 3350);
DISPLAY INVISIBLE (-5900 3350);
FORCEADD OFFPAGE_OUT..1
(-6000 3550);
FORCEPROP 2 LAST $XR0 11F5< 
J 0
(-5945 3550);
DISPLAY 0.638298 (-5945 3550);
PAINT MONO (-5945 3550);
FORCEPROP 1 LAST CDS_LMAN_SYM_OUTLINE -50,50,50,-50
J 0
(-6000 3550);
DISPLAY 0.468085 (-6000 3550);
PAINT GREEN (-6000 3550);
DISPLAY INVISIBLE (-6000 3550);
FORCEPROP 2 LAST CDS_LIB cls
J 0
(-6000 3550);
DISPLAY INVISIBLE (-6000 3550);
FORCEPROP 1 LAST BODY_TYPE COMMENT
J 0
(-5990 3685);
DISPLAY 0.808511 (-5990 3685);
PAINT GREEN (-5990 3685);
DISPLAY INVISIBLE (-5990 3685);
FORCEPROP 1 LAST OFFPAGE TRUE
J 0
(-5990 3605);
DISPLAY 0.808511 (-5990 3605);
PAINT GREEN (-5990 3605);
DISPLAY INVISIBLE (-5990 3605);
FORCEPROP 2 LAST PATH I65
J 0
(-5900 3600);
DISPLAY 1.021277 (-5900 3600);
DISPLAY INVISIBLE (-5900 3600);
FORCEADD CAPACITOR..1
R 3
(-9750 4550);
FORCEPROP 1 LAST $LOCATION C60
J 0
(-9650 4450);
DISPLAY 1.212766 (-9650 4450);
PAINT GREEN (-9650 4450);
FORCEPROP 0 LAST CDS_LOCATION C60
R 1
J 0
(-9650 4650);
DISPLAY 1.021277 (-9650 4650);
DISPLAY INVISIBLE (-9650 4650);
FORCEPROP 0 LAST $SEC 1
R 1
J 0
(-9650 4650);
DISPLAY 0.680851 (-9650 4650);
PAINT MONO (-9650 4650);
DISPLAY INVISIBLE (-9650 4650);
FORCEPROP 0 LAST CDS_SEC 1
R 1
J 0
(-9650 4650);
DISPLAY 1.021277 (-9650 4650);
DISPLAY INVISIBLE (-9650 4650);
FORCEPROP 0 LASTPIN (-9750 4650) $PN 1
R 1
J 0
(-9760 4660);
DISPLAY 0.680851 (-9760 4660);
PAINT MONO (-9760 4660);
FORCEPROP 0 LASTPIN (-9750 4400) $PN 2
R 1
J 2
(-9760 4390);
DISPLAY 0.680851 (-9760 4390);
PAINT MONO (-9760 4390);
FORCEPROP 0 LAST VOLTAGE 25V
J 0
(-9650 4750);
DISPLAY 1.021277 (-9650 4750);
FORCEPROP 1 LAST VALUE 0.1UF
J 0
(-9650 4550);
DISPLAY 1.212766 (-9650 4550);
PAINT GREEN (-9650 4550);
FORCEPROP 0 LAST PACKAGE 0402
J 0
(-9650 4650);
DISPLAY 1.021277 (-9650 4650);
FORCEPROP 1 LAST CLS_PN G105-0B104-EK
R 1
J 0
(-9850 4600);
DISPLAY 1.212766 (-9850 4600);
PAINT GREEN (-9850 4600);
DISPLAY INVISIBLE (-9850 4600);
FORCEPROP 1 LAST TOLERANCE 10%
R 1
J 0
(-9850 4650);
DISPLAY 1.212766 (-9850 4650);
PAINT GREEN (-9850 4650);
DISPLAY INVISIBLE (-9850 4650);
FORCEPROP 1 LAST CDS_LMAN_SYM_OUTLINE 0,50,50,-50
R 1
J 2
(-9750 4550);
DISPLAY 0.468085 (-9750 4550);
PAINT GREEN (-9750 4550);
DISPLAY INVISIBLE (-9750 4550);
FORCEPROP 2 LAST CDS_LIB passive
J 0
(-9750 4550);
DISPLAY INVISIBLE (-9750 4550);
FORCEPROP 1 LAST PATH I66
R 1
J 0
(-9850 4600);
DISPLAY 1.212766 (-9850 4600);
PAINT GREEN (-9850 4600);
DISPLAY INVISIBLE (-9850 4600);
FORCEADD OFFPAGE_OUT..1
R 2
(-8900 6550);
FORCEPROP 2 LAST $XR0 13E12< 
J 0
(-9114 6550);
DISPLAY 0.638298 (-9114 6550);
PAINT MONO (-9114 6550);
FORCEPROP 1 LAST BODY_TYPE COMMENT
J 2
(-8910 6685);
DISPLAY 0.808511 (-8910 6685);
PAINT GREEN (-8910 6685);
DISPLAY INVISIBLE (-8910 6685);
FORCEPROP 2 LAST CDS_LIB cls
J 0
(-8900 6550);
DISPLAY INVISIBLE (-8900 6550);
FORCEPROP 1 LAST CDS_LMAN_SYM_OUTLINE -50,50,50,-50
J 2
(-8900 6550);
DISPLAY 0.468085 (-8900 6550);
PAINT GREEN (-8900 6550);
DISPLAY INVISIBLE (-8900 6550);
FORCEPROP 1 LAST OFFPAGE TRUE
J 2
(-8910 6605);
DISPLAY 0.808511 (-8910 6605);
PAINT GREEN (-8910 6605);
DISPLAY INVISIBLE (-8910 6605);
FORCEPROP 2 LAST PATH I7
J 0
(-9050 6600);
DISPLAY 1.021277 (-9050 6600);
DISPLAY INVISIBLE (-9050 6600);
FORCEADD GND_SG..1
(-5400 6350);
FORCEPROP 3 LASTPIN (-5350 6400) SIG_NAME SG\g
J 0
(-5340 6410);
DISPLAY 0.659574 (-5340 6410);
PAINT MONO (-5340 6410);
DISPLAY INVISIBLE (-5340 6410);
FORCEPROP 1 LAST HDL_POWER SG
J 1
(-5350 6250);
DISPLAY 0.808511 (-5350 6250);
PAINT GREEN (-5350 6250);
FORCEPROP 1 LAST CDS_LMAN_SYM_OUTLINE 0,0,100,-50
J 0
(-5400 6350);
DISPLAY 0.468085 (-5400 6350);
PAINT GREEN (-5400 6350);
DISPLAY INVISIBLE (-5400 6350);
FORCEPROP 2 LAST CDS_LIB cls
J 0
(-5400 6350);
DISPLAY INVISIBLE (-5400 6350);
FORCEPROP 1 LAST BODY_TYPE PLUMBING
J 0
(-5385 6335);
DISPLAY 0.808511 (-5385 6335);
PAINT GREEN (-5385 6335);
DISPLAY INVISIBLE (-5385 6335);
FORCEPROP 1 LAST PATH I71
J 0
(-5365 6350);
DISPLAY 0.808511 (-5365 6350);
PAINT GREEN (-5365 6350);
DISPLAY INVISIBLE (-5365 6350);
FORCEADD GND_SG..1
(-650 2850);
FORCEPROP 3 LASTPIN (-600 2900) SIG_NAME SG\g
J 0
(-590 2910);
DISPLAY 0.659574 (-590 2910);
PAINT MONO (-590 2910);
DISPLAY INVISIBLE (-590 2910);
FORCEPROP 1 LAST HDL_POWER SG
J 1
(-595 2755);
DISPLAY 0.808511 (-595 2755);
PAINT GREEN (-595 2755);
FORCEPROP 2 LAST CDS_LIB cls
J 0
(-650 2850);
DISPLAY INVISIBLE (-650 2850);
FORCEPROP 1 LAST CDS_LMAN_SYM_OUTLINE 0,0,100,-50
J 0
(-650 2850);
DISPLAY 0.468085 (-650 2850);
PAINT GREEN (-650 2850);
DISPLAY INVISIBLE (-650 2850);
FORCEPROP 1 LAST BODY_TYPE PLUMBING
J 0
(-635 2835);
DISPLAY 0.808511 (-635 2835);
PAINT GREEN (-635 2835);
DISPLAY INVISIBLE (-635 2835);
FORCEPROP 1 LAST PATH I73
J 0
(-615 2850);
DISPLAY 0.808511 (-615 2850);
PAINT GREEN (-615 2850);
DISPLAY INVISIBLE (-615 2850);
FORCEADD CAPACITOR..2
(-600 3400);
FORCEPROP 1 LAST $LOCATION C69
J 0
(-500 3350);
DISPLAY 1.212766 (-500 3350);
PAINT GREEN (-500 3350);
FORCEPROP 0 LAST CDS_LOCATION C69
J 0
(-550 3500);
DISPLAY 1.021277 (-550 3500);
DISPLAY INVISIBLE (-550 3500);
FORCEPROP 0 LAST $SEC 1
J 0
(-550 3500);
DISPLAY 0.680851 (-550 3500);
PAINT MONO (-550 3500);
DISPLAY INVISIBLE (-550 3500);
FORCEPROP 0 LAST CDS_SEC 1
J 0
(-550 3500);
DISPLAY 1.021277 (-550 3500);
DISPLAY INVISIBLE (-550 3500);
FORCEPROP 0 LASTPIN (-600 3500) $PN 1
R 1
J 0
(-610 3510);
DISPLAY 0.680851 (-610 3510);
PAINT MONO (-610 3510);
FORCEPROP 0 LASTPIN (-600 3250) $PN 2
R 1
J 2
(-610 3240);
DISPLAY 0.680851 (-610 3240);
PAINT MONO (-610 3240);
FORCEPROP 1 LAST VALUE 0.1UF
J 0
(-550 3450);
DISPLAY 1.212766 (-550 3450);
PAINT GREEN (-550 3450);
FORCEPROP 0 LAST VOLTAGE 25V
J 0
(-550 3550);
DISPLAY 1.021277 (-550 3550);
FORCEPROP 0 LAST PACKAGE 0402
J 0
(-500 3250);
DISPLAY 1.021277 (-500 3250);
FORCEPROP 0 LAST NO_ASSY TRUE
J 0
(-850 3350);
DISPLAY 1.021277 (-850 3350);
DISPLAY BOTH (-850 3350);
FORCEPROP 1 LAST PATH I74
J 0
(-700 3450);
DISPLAY 1.212766 (-700 3450);
PAINT GREEN (-700 3450);
DISPLAY INVISIBLE (-700 3450);
FORCEPROP 1 LAST TOLERANCE 10%
J 0
(-750 3500);
DISPLAY 1.212766 (-750 3500);
PAINT GREEN (-750 3500);
DISPLAY INVISIBLE (-750 3500);
FORCEPROP 1 LAST CDS_LMAN_SYM_OUTLINE -50,0,50,-50
J 0
(-600 3400);
DISPLAY 0.468085 (-600 3400);
PAINT GREEN (-600 3400);
DISPLAY INVISIBLE (-600 3400);
FORCEPROP 2 LAST CDS_LIB passive
J 0
(-600 3400);
DISPLAY INVISIBLE (-600 3400);
FORCEPROP 1 LAST CLS_PN G105-0B104-EK
J 0
(-700 3450);
DISPLAY 1.212766 (-700 3450);
PAINT GREEN (-700 3450);
DISPLAY INVISIBLE (-700 3450);
FORCEADD CAPACITOR..2
(-200 3400);
FORCEPROP 1 LAST $LOCATION C70
J 0
(-150 3250);
DISPLAY 1.212766 (-150 3250);
PAINT GREEN (-150 3250);
FORCEPROP 0 LAST CDS_LOCATION C70
J 0
(-150 3550);
DISPLAY 1.021277 (-150 3550);
DISPLAY INVISIBLE (-150 3550);
FORCEPROP 0 LAST $SEC 1
J 0
(-150 3550);
DISPLAY 0.680851 (-150 3550);
PAINT MONO (-150 3550);
DISPLAY INVISIBLE (-150 3550);
FORCEPROP 0 LAST CDS_SEC 1
J 0
(-150 3550);
DISPLAY 1.021277 (-150 3550);
DISPLAY INVISIBLE (-150 3550);
FORCEPROP 0 LASTPIN (-200 3500) $PN 1
R 1
J 0
(-210 3510);
DISPLAY 0.680851 (-210 3510);
PAINT MONO (-210 3510);
FORCEPROP 0 LASTPIN (-200 3250) $PN 2
R 1
J 2
(-210 3240);
DISPLAY 0.680851 (-210 3240);
PAINT MONO (-210 3240);
FORCEPROP 0 LAST VOLTAGE 25V
J 0
(-150 3550);
DISPLAY 1.021277 (-150 3550);
FORCEPROP 1 LAST VALUE 0.1UF
J 0
(-150 3450);
DISPLAY 1.212766 (-150 3450);
PAINT GREEN (-150 3450);
FORCEPROP 0 LAST PACKAGE 0402
J 0
(-100 3350);
DISPLAY 1.021277 (-100 3350);
FORCEPROP 1 LAST PATH I77
J 0
(-300 3450);
DISPLAY 1.212766 (-300 3450);
PAINT GREEN (-300 3450);
DISPLAY INVISIBLE (-300 3450);
FORCEPROP 1 LAST TOLERANCE 10%
J 0
(-350 3500);
DISPLAY 1.212766 (-350 3500);
PAINT GREEN (-350 3500);
DISPLAY INVISIBLE (-350 3500);
FORCEPROP 1 LAST CDS_LMAN_SYM_OUTLINE -50,0,50,-50
J 0
(-200 3400);
DISPLAY 0.468085 (-200 3400);
PAINT GREEN (-200 3400);
DISPLAY INVISIBLE (-200 3400);
FORCEPROP 2 LAST CDS_LIB passive
J 0
(-200 3400);
DISPLAY INVISIBLE (-200 3400);
FORCEPROP 1 LAST CLS_PN G105-0B104-EK
J 0
(-300 3450);
DISPLAY 1.212766 (-300 3450);
PAINT GREEN (-300 3450);
DISPLAY INVISIBLE (-300 3450);
FORCEADD TPS2051BDBVT_SOT23_5..2
(250 3500);
FORCEPROP 1 LAST $LOCATION U12
J 2
(950 3350);
DISPLAY 1.212766 (950 3350);
PAINT GREEN (950 3350);
FORCEPROP 0 LAST CDS_LOCATION U12
J 0
(1500 3350);
DISPLAY 1.021277 (1500 3350);
DISPLAY INVISIBLE (1500 3350);
FORCEPROP 0 LAST $SEC 2
J 0
(1500 3350);
DISPLAY 0.680851 (1500 3350);
PAINT MONO (1500 3350);
DISPLAY INVISIBLE (1500 3350);
FORCEPROP 0 LAST CDS_SEC 2
J 0
(1500 3350);
DISPLAY 1.021277 (1500 3350);
DISPLAY INVISIBLE (1500 3350);
FORCEPROP 0 LASTPIN (450 3000) $PN 2
R 1
J 2
(440 2990);
DISPLAY 0.680851 (440 2990);
PAINT MONO (440 2990);
FORCEPROP 0 LAST VENDOR_PN TPS2051BDBVT
J 0
(800 3150);
FORCEPROP 1 LAST CLS_PN G220-10338-01
J 2
(1500 3250);
DISPLAY 1.212766 (1500 3250);
PAINT GREEN (1500 3250);
FORCEPROP 1 LAST CDS_LMAN_SYM_OUTLINE 0,0,400,-400
J 0
(250 3500);
DISPLAY 0.468085 (250 3500);
PAINT GREEN (250 3500);
DISPLAY INVISIBLE (250 3500);
FORCEPROP 2 LAST CDS_LIB stdlogic
J 0
(250 3500);
DISPLAY INVISIBLE (250 3500);
FORCEPROP 1 LAST PATH I78
J 2
(200 3550);
DISPLAY 1.212766 (200 3550);
PAINT GREEN (200 3550);
DISPLAY INVISIBLE (200 3550);
FORCEADD TPS2051BDBVT_SOT23_5..1
(225 4100);
FORCEPROP 1 LAST $LOCATION U12
J 0
(200 4350);
DISPLAY 1.212766 (200 4350);
PAINT GREEN (200 4350);
FORCEPROP 0 LAST CDS_LOCATION U12
J 0
(450 4300);
DISPLAY 1.021277 (450 4300);
DISPLAY INVISIBLE (450 4300);
FORCEPROP 0 LAST $SEC 1
J 0
(450 4300);
DISPLAY 0.680851 (450 4300);
PAINT MONO (450 4300);
DISPLAY INVISIBLE (450 4300);
FORCEPROP 0 LAST CDS_SEC 1
J 0
(450 4300);
DISPLAY 1.021277 (450 4300);
DISPLAY INVISIBLE (450 4300);
FORCEPROP 0 LASTPIN (125 3800) $PN 4
J 2
(115 3810);
DISPLAY 0.680851 (115 3810);
PAINT MONO (115 3810);
FORCEPROP 0 LASTPIN (125 4000) $PN 5
J 2
(115 4010);
DISPLAY 0.680851 (115 4010);
PAINT MONO (115 4010);
FORCEPROP 0 LASTPIN (825 3800) $PN 3
J 0
(835 3810);
DISPLAY 0.680851 (835 3810);
PAINT MONO (835 3810);
FORCEPROP 0 LASTPIN (825 4000) $PN 1
J 0
(835 4010);
DISPLAY 0.680851 (835 4010);
PAINT MONO (835 4010);
FORCEPROP 0 LAST VENDOR_PN TPS2051BDBVT
J 0
(200 4250);
FORCEPROP 1 LAST CLS_PN G220-10338-01
J 0
(200 4150);
DISPLAY 1.212766 (200 4150);
PAINT GREEN (200 4150);
FORCEPROP 1 LAST CDS_LMAN_SYM_OUTLINE 0,0,500,-500
J 0
(225 4100);
DISPLAY 0.468085 (225 4100);
PAINT GREEN (225 4100);
DISPLAY INVISIBLE (225 4100);
FORCEPROP 2 LAST CDS_LIB stdlogic
J 0
(225 4100);
DISPLAY INVISIBLE (225 4100);
FORCEPROP 1 LAST PATH I79
J 0
(275 4150);
DISPLAY 1.212766 (275 4150);
PAINT GREEN (275 4150);
DISPLAY INVISIBLE (275 4150);
FORCEADD RESISTOR..2
R 1
(1350 4150);
FORCEPROP 1 LAST $LOCATION R107
J 0
(1050 4250);
DISPLAY 1.212766 (1050 4250);
PAINT GREEN (1050 4250);
FORCEPROP 0 LAST CDS_LOCATION R107
R 1
J 0
(1200 4200);
DISPLAY 1.021277 (1200 4200);
DISPLAY INVISIBLE (1200 4200);
FORCEPROP 0 LAST $SEC 1
R 1
J 0
(1200 4200);
DISPLAY 0.680851 (1200 4200);
PAINT MONO (1200 4200);
DISPLAY INVISIBLE (1200 4200);
FORCEPROP 0 LAST CDS_SEC 1
R 1
J 0
(1200 4200);
DISPLAY 1.021277 (1200 4200);
DISPLAY INVISIBLE (1200 4200);
FORCEPROP 0 LASTPIN (1250 4150) $PN 1
J 2
(1240 4160);
DISPLAY 0.680851 (1240 4160);
PAINT MONO (1240 4160);
FORCEPROP 0 LASTPIN (1500 4150) $PN 2
J 0
(1540 4160);
DISPLAY 0.680851 (1540 4160);
PAINT MONO (1540 4160);
FORCEPROP 0 LAST PACKAGE 0402
J 0
(1300 4200);
DISPLAY 1.021277 (1300 4200);
FORCEPROP 1 LAST VALUE 4.7KOHM
J 0
(1550 4250);
DISPLAY 1.212766 (1550 4250);
PAINT GREEN (1550 4250);
FORCEPROP 1 LAST CLS_PN G155-14701-01
R 1
J 0
(1150 4014);
DISPLAY 1.212766 (1150 4014);
PAINT GREEN (1150 4014);
DISPLAY INVISIBLE (1150 4014);
FORCEPROP 2 LAST CDS_LIB passive
R 1
J 0
(1350 4150);
DISPLAY INVISIBLE (1350 4150);
FORCEPROP 1 LAST CDS_LMAN_SYM_OUTLINE -50,50,50,-100
R 1
J 0
(1350 4150);
DISPLAY 0.468085 (1350 4150);
PAINT GREEN (1350 4150);
DISPLAY INVISIBLE (1350 4150);
FORCEPROP 1 LAST TOLERANCE 1%
R 1
J 0
(1095 3953);
DISPLAY 1.212766 (1095 3953);
PAINT GREEN (1095 3953);
DISPLAY INVISIBLE (1095 3953);
FORCEPROP 1 LAST PATH I83
R 1
J 0
(1245 3953);
DISPLAY 1.212766 (1245 3953);
PAINT GREEN (1245 3953);
DISPLAY INVISIBLE (1245 3953);
FORCEADD CAPACITOR..2
(2250 3550);
FORCEPROP 1 LAST $LOCATION C71
J 0
(2300 3400);
DISPLAY 1.212766 (2300 3400);
PAINT GREEN (2300 3400);
FORCEPROP 0 LAST CDS_LOCATION C71
J 0
(2300 3700);
DISPLAY 1.021277 (2300 3700);
DISPLAY INVISIBLE (2300 3700);
FORCEPROP 0 LAST $SEC 1
J 0
(2300 3700);
DISPLAY 0.680851 (2300 3700);
PAINT MONO (2300 3700);
DISPLAY INVISIBLE (2300 3700);
FORCEPROP 0 LAST CDS_SEC 1
J 0
(2300 3700);
DISPLAY 1.021277 (2300 3700);
DISPLAY INVISIBLE (2300 3700);
FORCEPROP 0 LASTPIN (2250 3650) $PN 1
R 1
J 0
(2240 3660);
DISPLAY 0.680851 (2240 3660);
PAINT MONO (2240 3660);
FORCEPROP 0 LASTPIN (2250 3400) $PN 2
R 1
J 2
(2240 3390);
DISPLAY 0.680851 (2240 3390);
PAINT MONO (2240 3390);
FORCEPROP 0 LAST VOLTAGE 25V
J 0
(2300 3750);
DISPLAY 1.021277 (2300 3750);
FORCEPROP 1 LAST VALUE 0.1UF
J 0
(2300 3600);
DISPLAY 1.212766 (2300 3600);
PAINT GREEN (2300 3600);
FORCEPROP 0 LAST PACKAGE 0402
J 0
(2400 3500);
DISPLAY 1.021277 (2400 3500);
FORCEPROP 1 LAST PATH I85
J 0
(2150 3600);
DISPLAY 1.212766 (2150 3600);
PAINT GREEN (2150 3600);
DISPLAY INVISIBLE (2150 3600);
FORCEPROP 1 LAST CLS_PN G105-0B104-EK
J 0
(2150 3600);
DISPLAY 1.212766 (2150 3600);
PAINT GREEN (2150 3600);
DISPLAY INVISIBLE (2150 3600);
FORCEPROP 1 LAST CDS_LMAN_SYM_OUTLINE -50,0,50,-50
J 0
(2250 3550);
DISPLAY 0.468085 (2250 3550);
PAINT GREEN (2250 3550);
DISPLAY INVISIBLE (2250 3550);
FORCEPROP 2 LAST CDS_LIB passive
J 0
(2250 3550);
DISPLAY INVISIBLE (2250 3550);
FORCEPROP 1 LAST TOLERANCE 10%
J 0
(2100 3650);
DISPLAY 1.212766 (2100 3650);
PAINT GREEN (2100 3650);
DISPLAY INVISIBLE (2100 3650);
FORCEADD VCC..1
(-250 4250);
FORCEPROP 3 LASTPIN (-200 4200) SIG_NAME XP5R0V_MAC\g
J 0
(-190 4210);
DISPLAY 0.659574 (-190 4210);
PAINT MONO (-190 4210);
DISPLAY INVISIBLE (-190 4210);
FORCEPROP 0 LAST VOLTAGE 5
J 1
(-200 4350);
DISPLAY 1.021277 (-200 4350);
DISPLAY BOTH (-200 4350);
FORCEPROP 1 LAST HDL_POWER XP5R0V_MAC
J 1
(-200 4300);
DISPLAY 0.808511 (-200 4300);
PAINT GREEN (-200 4300);
FORCEPROP 2 LAST CDS_LIB cls
J 0
(-250 4250);
DISPLAY INVISIBLE (-250 4250);
FORCEPROP 1 LAST CDS_LMAN_SYM_OUTLINE -250,250,250,-250
J 0
(-250 4250);
DISPLAY 0.468085 (-250 4250);
PAINT GREEN (-250 4250);
DISPLAY INVISIBLE (-250 4250);
FORCEPROP 1 LAST BODY_TYPE PLUMBING
J 0
(-295 4207);
DISPLAY 0.340426 (-295 4207);
PAINT GREEN (-295 4207);
DISPLAY INVISIBLE (-295 4207);
FORCEPROP 1 LAST PATH I88
J 0
(-215 4340);
DISPLAY 0.808511 (-215 4340);
PAINT GREEN (-215 4340);
DISPLAY INVISIBLE (-215 4340);
FORCEADD VCC..1
(2200 4350);
FORCEPROP 3 LASTPIN (2250 4300) SIG_NAME XP5R0V_MAC_USB\g
J 0
(2260 4310);
DISPLAY 0.659574 (2260 4310);
PAINT MONO (2260 4310);
DISPLAY INVISIBLE (2260 4310);
FORCEPROP 0 LAST VOLTAGE 5V
J 0
(2000 4450);
DISPLAY BOTH (2000 4450);
FORCEPROP 1 LAST HDL_POWER XP5R0V_MAC_USB
J 1
(2255 4405);
DISPLAY 0.808511 (2255 4405);
PAINT GREEN (2255 4405);
FORCEPROP 2 LAST CDS_LIB cls
J 0
(2200 4350);
DISPLAY INVISIBLE (2200 4350);
FORCEPROP 1 LAST CDS_LMAN_SYM_OUTLINE -250,250,250,-250
J 0
(2200 4350);
DISPLAY 0.468085 (2200 4350);
PAINT GREEN (2200 4350);
DISPLAY INVISIBLE (2200 4350);
FORCEPROP 1 LAST BODY_TYPE PLUMBING
J 0
(2155 4307);
DISPLAY 0.340426 (2155 4307);
PAINT GREEN (2155 4307);
DISPLAY INVISIBLE (2155 4307);
FORCEPROP 1 LAST PATH I89
J 0
(2235 4440);
DISPLAY 0.808511 (2235 4440);
PAINT GREEN (2235 4440);
DISPLAY INVISIBLE (2235 4440);
FORCEADD FERRITEBEAD..1
(-8050 4800);
FORCEPROP 1 LAST $LOCATION L3
J 2
(-8100 4800);
DISPLAY 1.212766 (-8100 4800);
PAINT GREEN (-8100 4800);
FORCEPROP 0 LAST CDS_LOCATION L3
J 0
(-7700 4900);
DISPLAY 1.021277 (-7700 4900);
DISPLAY INVISIBLE (-7700 4900);
FORCEPROP 0 LAST $SEC 1
J 0
(-7700 4900);
DISPLAY 0.680851 (-7700 4900);
PAINT MONO (-7700 4900);
DISPLAY INVISIBLE (-7700 4900);
FORCEPROP 0 LAST CDS_SEC 1
J 0
(-7700 4900);
DISPLAY 1.021277 (-7700 4900);
DISPLAY INVISIBLE (-7700 4900);
FORCEPROP 0 LASTPIN (-8150 4750) $PN 1
J 2
(-8160 4760);
DISPLAY 0.680851 (-8160 4760);
PAINT MONO (-8160 4760);
FORCEPROP 0 LASTPIN (-7750 4750) $PN 2
J 0
(-7740 4760);
DISPLAY 0.680851 (-7740 4760);
PAINT MONO (-7740 4760);
FORCEPROP 1 LAST VALUE 26OHM
J 0
(-7700 4800);
DISPLAY 1.212766 (-7700 4800);
PAINT GREEN (-7700 4800);
FORCEPROP 0 LAST PACKAGE 0805
J 0
(-8000 4850);
DISPLAY 1.021277 (-8000 4850);
FORCEPROP 1 LAST CDS_LMAN_SYM_OUTLINE 0,0,200,-100
J 0
(-8050 4800);
DISPLAY 0.468085 (-8050 4800);
PAINT GREEN (-8050 4800);
DISPLAY INVISIBLE (-8050 4800);
FORCEPROP 2 LAST CDS_LIB passive
J 0
(-8050 4800);
DISPLAY INVISIBLE (-8050 4800);
FORCEPROP 1 LAST PATH I91
J 2
(-8100 4850);
DISPLAY 1.212766 (-8100 4850);
PAINT GREEN (-8100 4850);
DISPLAY INVISIBLE (-8100 4850);
FORCEPROP 1 LAST TOLERANCE 25%
J 0
(-8150 4850);
DISPLAY 1.212766 (-8150 4850);
PAINT GREEN (-8150 4850);
DISPLAY INVISIBLE (-8150 4850);
FORCEPROP 1 LAST CLS_PN G191-10101-01
J 2
(-8100 4850);
DISPLAY 1.212766 (-8100 4850);
PAINT GREEN (-8100 4850);
DISPLAY INVISIBLE (-8100 4850);
FORCEADD VCC..1
(-7200 5000);
FORCEPROP 3 LASTPIN (-7150 4950) SIG_NAME XP5R0V\g
J 0
(-7140 4960);
DISPLAY 0.659574 (-7140 4960);
PAINT MONO (-7140 4960);
DISPLAY INVISIBLE (-7140 4960);
FORCEPROP 1 LAST HDL_POWER XP5R0V
J 1
(-7145 5055);
DISPLAY 1.021277 (-7145 5055);
PAINT GREEN (-7145 5055);
FORCEPROP 0 LAST VOLTAGE 5.0
J 0
(-7400 5150);
DISPLAY 1.021277 (-7400 5150);
DISPLAY BOTH (-7400 5150);
FORCEPROP 2 LAST CDS_LIB cls
J 0
(-7200 5000);
DISPLAY INVISIBLE (-7200 5000);
FORCEPROP 1 LAST CDS_LMAN_SYM_OUTLINE -250,250,250,-250
J 0
(-7200 5000);
DISPLAY 0.468085 (-7200 5000);
PAINT GREEN (-7200 5000);
DISPLAY INVISIBLE (-7200 5000);
FORCEPROP 1 LAST BODY_TYPE PLUMBING
J 0
(-7245 4957);
DISPLAY 0.340426 (-7245 4957);
PAINT GREEN (-7245 4957);
DISPLAY INVISIBLE (-7245 4957);
FORCEPROP 1 LAST PATH I92
J 0
(-7165 5090);
DISPLAY 0.808511 (-7165 5090);
PAINT GREEN (-7165 5090);
DISPLAY INVISIBLE (-7165 5090);
FORCEADD CAPACITOR..1
R 3
(-7550 4550);
FORCEPROP 1 LAST $LOCATION C62
J 0
(-7450 4350);
DISPLAY 1.212766 (-7450 4350);
PAINT GREEN (-7450 4350);
FORCEPROP 0 LAST CDS_LOCATION C62
R 1
J 0
(-7450 4650);
DISPLAY 1.021277 (-7450 4650);
DISPLAY INVISIBLE (-7450 4650);
FORCEPROP 0 LAST $SEC 1
R 1
J 0
(-7450 4650);
DISPLAY 0.680851 (-7450 4650);
PAINT MONO (-7450 4650);
DISPLAY INVISIBLE (-7450 4650);
FORCEPROP 0 LAST CDS_SEC 1
R 1
J 0
(-7450 4650);
DISPLAY 1.021277 (-7450 4650);
DISPLAY INVISIBLE (-7450 4650);
FORCEPROP 0 LASTPIN (-7550 4650) $PN 1
R 1
J 0
(-7560 4660);
DISPLAY 0.680851 (-7560 4660);
PAINT MONO (-7560 4660);
FORCEPROP 0 LASTPIN (-7550 4400) $PN 2
R 1
J 2
(-7560 4390);
DISPLAY 0.680851 (-7560 4390);
PAINT MONO (-7560 4390);
FORCEPROP 0 LAST PACKAGE 0402
J 0
(-7450 4550);
DISPLAY 1.021277 (-7450 4550);
FORCEPROP 0 LAST VOLTAGE 25V
J 0
(-7450 4650);
DISPLAY 1.021277 (-7450 4650);
FORCEPROP 1 LAST VALUE 0.1UF
J 0
(-7450 4450);
DISPLAY 1.212766 (-7450 4450);
PAINT GREEN (-7450 4450);
FORCEPROP 1 LAST CLS_PN G105-0B104-EK
R 1
J 0
(-7650 4600);
DISPLAY 1.212766 (-7650 4600);
PAINT GREEN (-7650 4600);
DISPLAY INVISIBLE (-7650 4600);
FORCEPROP 1 LAST TOLERANCE 10%
R 1
J 0
(-7650 4650);
DISPLAY 1.212766 (-7650 4650);
PAINT GREEN (-7650 4650);
DISPLAY INVISIBLE (-7650 4650);
FORCEPROP 2 LAST CDS_LIB passive
J 0
(-7550 4550);
DISPLAY INVISIBLE (-7550 4550);
FORCEPROP 1 LAST CDS_LMAN_SYM_OUTLINE 0,50,50,-50
R 1
J 2
(-7550 4550);
DISPLAY 0.468085 (-7550 4550);
PAINT GREEN (-7550 4550);
DISPLAY INVISIBLE (-7550 4550);
FORCEPROP 1 LAST PATH I93
R 1
J 0
(-7650 4600);
DISPLAY 1.212766 (-7650 4600);
PAINT GREEN (-7650 4600);
DISPLAY INVISIBLE (-7650 4600);
FORCEADD GND_SG..1
(-2450 -200);
FORCEPROP 3 LASTPIN (-2400 -150) SIG_NAME SG\g
J 0
(-2390 -140);
DISPLAY 0.659574 (-2390 -140);
PAINT MONO (-2390 -140);
DISPLAY INVISIBLE (-2390 -140);
FORCEPROP 1 LAST HDL_POWER SG
J 1
(-2395 -295);
DISPLAY 0.808511 (-2395 -295);
PAINT GREEN (-2395 -295);
FORCEPROP 0 LAST VOLTAGE 0
J 0
(-2350 -200);
DISPLAY 1.021277 (-2350 -200);
DISPLAY INVISIBLE (-2350 -200);
FORCEPROP 1 LAST CDS_LMAN_SYM_OUTLINE 0,0,100,-50
J 0
(-2450 -200);
DISPLAY 0.468085 (-2450 -200);
PAINT GREEN (-2450 -200);
DISPLAY INVISIBLE (-2450 -200);
FORCEPROP 2 LAST CDS_LIB cls
J 0
(-2450 -200);
DISPLAY INVISIBLE (-2450 -200);
FORCEPROP 1 LAST BODY_TYPE PLUMBING
J 0
(-2435 -215);
DISPLAY 0.808511 (-2435 -215);
PAINT GREEN (-2435 -215);
DISPLAY INVISIBLE (-2435 -215);
FORCEPROP 1 LAST PATH I96
J 0
(-2415 -200);
DISPLAY 0.808511 (-2415 -200);
PAINT GREEN (-2415 -200);
DISPLAY INVISIBLE (-2415 -200);
FORCEADD SHEET_A1..1
(3000 -1350);
FORCEPROP 2 LAST CUSTOM_TXT_CDS <XR_PAGE_TITLE>
J 0
(-12570 10000);
DISPLAY 0.638298 (-12570 10000);
PAINT PINK (-12570 10000);
FORCEPROP 1 LAST CUSTOM_TXT_CDS <DOCNO>
J 0
(950 -965);
DISPLAY 0.978723 (950 -965);
FORCEPROP 1 LAST CUSTOM_TXT_CDS <CON_PAGE_NUM>
J 0
(845 -1300);
DISPLAY 0.978723 (845 -1300);
FORCEPROP 1 LAST CUSTOM_TXT_CDS <DATE>
J 0
(2300 -1175);
DISPLAY 0.978723 (2300 -1175);
FORCEPROP 1 LAST CUSTOM_TXT_CDS <TITLE>
J 1
(1215 -720);
DISPLAY 0.978723 (1215 -720);
FORCEPROP 1 LAST CUSTOM_TXT_CDS <DESIGNER>
J 0
(2300 -750);
DISPLAY 0.978723 (2300 -750);
FORCEPROP 1 LAST CUSTOM_TXT_CDS <CON_TOTAL_PAGES>
J 0
(1155 -1300);
DISPLAY 0.808511 (1155 -1300);
FORCEPROP 1 LAST CUSTOM_TXT_CDS <ASSY_PN>
J 0
(950 -1175);
DISPLAY 0.978723 (950 -1175);
FORCEPROP 1 LAST CUSTOM_TXT_CDS <DOCREV>
J 0
(2300 -975);
DISPLAY 0.978723 (2300 -975);
FORCEPROP 1 LAST TITLE MAC_MODULE_CONN
J 0
(500 -450);
DISPLAY 3.042553 (500 -450);
PAINT GREEN (500 -450);
FORCEPROP 2 LAST PAGE_BORDER TRUE
J 0
(-12570 10000);
DISPLAY 0.638298 (-12570 10000);
PAINT PINK (-12570 10000);
DISPLAY INVISIBLE (-12570 10000);
FORCEPROP 1 LAST CDS_LMAN_SYM_OUTLINE -15850,11500,200,-200
J 0
(3000 -1350);
DISPLAY 0.468085 (3000 -1350);
PAINT GREEN (3000 -1350);
DISPLAY INVISIBLE (3000 -1350);
FORCEPROP 2 LAST CDS_LIB cls
J 0
(3000 -1350);
DISPLAY INVISIBLE (3000 -1350);
FORCEPROP 1 LAST COMMENT_BODY TRUE
J 0
(3010 -1295);
DISPLAY 0.808511 (3010 -1295);
DISPLAY INVISIBLE (3010 -1295);
FORCEPROP 2 LAST CDS_XR_PAGE_TITLE CR-21 : @TIMECARD_LIB.TIMECARD(SCH_1):PAGE21
J 0
(-12570 10000);
DISPLAY 0.638298 (-12570 10000);
PAINT PINK (-12570 10000);
DISPLAY INVISIBLE (-12570 10000);
WIRE 16 -1 (-2400 -50)(-2400 -150);
WIRE 16 -1 (-2400 -50)(-2500 -50);
WIRE 16 -1 (125 4000)(-200 4000);
WIRE 16 -1 (-200 4000)(-200 4200);
WIRE 16 -1 (-200 3500)(-200 4000);
WIRE 16 -1 (1850 1850)(2150 1850);
WIRE 16 -1 (2150 1850)(2150 2100);
WIRE 16 -1 (-1250 6700)(-1250 6800);
WIRE 16 -1 (-1250 6700)(-1800 6700);
WIRE 16 -1 (-2350 3250)(-2350 2950);
WIRE 16 -1 (-3500 -350)(-3500 -250);
WIRE 16 -1 (-4650 950)(-4450 950);
WIRE 16 -1 (-4650 950)(-4650 850);
WIRE 16 -1 (-7150 4750)(-7550 4750);
WIRE 16 -1 (-7150 4950)(-7150 4750);
WIRE 16 -1 (-7550 4650)(-7550 4750);
WIRE 16 -1 (-7550 4750)(-7750 4750);
WIRE 16 -1 (2250 4300)(2250 4000);
WIRE 16 -1 (2250 4000)(2250 3650);
WIRE 16 -1 (825 4000)(2250 4000);
WIRE 16 -1 (2250 3400)(2250 2925);
WIRE 16 -1 (2250 2925)(450 2925);
WIRE 16 -1 (450 3000)(450 2925);
WIRE 16 -1 (-200 2925)(450 2925);
WIRE 16 -1 (-200 3250)(-200 2925);
WIRE 16 -1 (-600 2925)(-200 2925);
WIRE 16 -1 (-600 3250)(-600 2925);
WIRE 16 -1 (-600 2925)(-600 2900);
WIRE 16 -1 (-5250 6750)(-5350 6750);
WIRE 16 -1 (-5350 6750)(-5350 7050);
WIRE 16 -1 (-5350 6400)(-5350 6750);
WIRE 16 -1 (-5250 7050)(-5350 7050);
WIRE 16 -1 (-3200 6850)(-3200 6950);
WIRE 16 -1 (-3700 6850)(-3200 6850);
WIRE 16 -1 (-3700 6850)(-4200 6850);
WIRE 16 -1 (-3700 6850)(-3700 6950);
WIRE 16 -1 (-4200 6950)(-4200 6850);
WIRE 16 -1 (-4200 6850)(-4200 6800);
WIRE 16 -1 (-4300 7900)(-4300 7250);
WIRE 16 -1 (-4300 7250)(-4200 7250);
WIRE 16 -1 (-4550 7250)(-4300 7250);
WIRE 16 -1 (-4200 7250)(-3700 7250);
WIRE 16 -1 (-4200 7200)(-4200 7250);
WIRE 16 -1 (-3200 7250)(-3700 7250);
WIRE 16 -1 (-3700 7250)(-3700 7200);
WIRE 16 -1 (-3200 7200)(-3200 7250);
WIRE 16 -1 (-10200 4750)(-10400 4750);
WIRE 16 -1 (-10200 4750)(-9750 4750);
WIRE 16 -1 (-10200 4750)(-10200 4650);
WIRE 16 -1 (-10400 4750)(-10400 4950);
WIRE 16 -1 (-10400 4750)(-10850 4750);
WIRE 16 -1 (-9250 4750)(-9750 4750);
WIRE 16 -1 (-9750 4650)(-9750 4750);
WIRE 16 -1 (-8800 4750)(-9250 4750);
WIRE 16 -1 (-9250 4650)(-9250 4750);
WIRE 16 -1 (-8800 4750)(-8350 4750);
WIRE 16 -1 (-8800 4650)(-8800 4750);
WIRE 16 -1 (-8150 4750)(-8350 4750);
WIRE 16 -1 (-8350 4650)(-8350 4750);
WIRE 16 -1 (-10200 4400)(-10200 4300);
WIRE 16 -1 (-10200 4300)(-9750 4300);
WIRE 16 -1 (-10200 4250)(-10200 4300);
WIRE 16 -1 (-9250 4300)(-9750 4300);
WIRE 16 -1 (-9750 4300)(-9750 4400);
WIRE 16 -1 (-8800 4300)(-9250 4300);
WIRE 16 -1 (-9250 4400)(-9250 4300);
WIRE 16 -1 (-8800 4300)(-8350 4300);
WIRE 16 -1 (-8800 4400)(-8800 4300);
WIRE 16 -1 (-7550 4300)(-8350 4300);
WIRE 16 -1 (-8350 4400)(-8350 4300);
WIRE 16 -1 (-7550 4300)(-7550 4400);
WIRE 16 -1 (-10600 4400)(-10600 4150);
WIRE 16 -1 (-10600 4400)(-10850 4400);
WIRE 16 -1 (-10850 4150)(-10600 4150);
WIRE 16 -1 (-10600 2450)(-10600 4150);
WIRE 16 -1 (-11100 300)(-11000 300);
WIRE 16 -1 (-11000 300)(-11000 -550);
WIRE 16 -1 (-11000 -550)(-10600 -550);
WIRE 16 -1 (-11000 -600)(-11000 -550);
WIRE 16 -1 (-8900 -550)(-10600 -550);
WIRE 16 -1 (-10600 -250)(-10600 -550);
WIRE 16 -1 (-8900 0)(-8900 -550);
WIRE 16 -1 (-8900 -550)(-8500 -550);
WIRE 16 -1 (-8500 0)(-8500 -550);
WIRE 16 -1 (-8050 -550)(-8500 -550);
WIRE 16 -1 (-8050 -450)(-8050 -550);
WIRE 16 -1 (100 600)(200 600);
WIRE 16 -1 (100 550)(100 600);
WIRE 16 -1 (100 1500)(100 1850);
WIRE 16 -1 (100 2100)(100 1850);
WIRE 16 -1 (600 1850)(100 1850);
WIRE 16 -1 (650 1850)(600 1850);
WIRE 16 -1 (600 1750)(600 1850);
WIRE 16 -1 (-9200 2500)(-9600 2500);
WIRE 16 -1 (-9600 2500)(-9600 2400);
WIRE 16 -1 (-9600 2400)(-9200 2400);
WIRE 16 -1 (-9900 2400)(-9600 2400);
WIRE 16 -1 (-9900 2400)(-9900 2450);
WIRE 16 -1 (-4550 7150)(-4450 7150);
WIRE 16 -1 (-4450 6400)(-4450 7150);
WIRE 16 -1 (-8050 600)(-8050 700);
WIRE 16 -1 (-8050 800)(-8050 700);
WIRE 16 -1 (-8050 700)(-8500 700);
WIRE 16 -1 (-8500 250)(-8500 700);
WIRE 16 -1 (-8900 700)(-8500 700);
WIRE 16 -1 (-8900 700)(-10600 700);
WIRE 16 -1 (-8900 250)(-8900 700);
WIRE 16 -1 (-10600 700)(-10600 400);
WIRE 16 -1 (-10600 700)(-11100 700);
WIRE 16 -1 (-5200 3900)(-5050 3900);
WIRE 16 -1 (-5050 3900)(-5050 3700);
WIRE 16 -1 (-5050 3700)(-5050 3600);
WIRE 16 -1 (-5050 3700)(-5200 3700);
WIRE 16 -1 (-4200 950)(-4000 950);
WIRE 16 -1 (-4000 1100)(-4000 950);
WIRE 16 -1 (-4000 950)(-4000 850);
WIRE 16 -1 (-4000 850)(-3400 850);
WIRE 16 -1 (-1650 3300)(-1650 3350);
WIRE 16 -1 (-1100 3350)(-1650 3350);
WIRE 16 -1 (-1100 3350)(-1100 3400);
WIRE 16 -1 (-1100 3100)(-1100 3350);
WIRE 16 -1 (1000 4150)(1250 4150);
WIRE 16 -1 (1000 4350)(1000 4150);
WIRE 16 -1 (-1650 2600)(-1650 2550);
WIRE 16 -1 (-1650 2550)(-1100 2550);
WIRE 16 -1 (-1100 2550)(-1100 2850);
WIRE 16 -1 (-1100 2550)(-1100 2500);
WIRE 16 -1 (-11700 100)(-11850 100);
WIRE 16 -1 (-11850 100)(-11850 200);
WIRE 16 -1 (-11850 0)(-11850 100);
WIRE 16 -1 (-11700 200)(-11850 200);
WIRE 16 -1 (-11850 200)(-11850 300);
WIRE 16 -1 (-11700 300)(-11850 300);
WIRE 16 -1 (-11850 300)(-11850 400);
WIRE 16 -1 (-11700 400)(-11850 400);
WIRE 16 -1 (-11850 400)(-11850 600);
WIRE 16 -1 (-11700 600)(-11850 600);
WIRE 16 -1 (-11850 700)(-11850 600);
WIRE 16 -1 (-11850 700)(-11700 700);
WIRE 16 -1 (-8150 3800)(-10850 3800);
FORCEPROP 2 LAST SIG_NAME ANALOG_TUNING_IN
J 0
(-10110 3810);
DISPLAY 1.021277 (-10110 3810);
WIRE 16 273 (2750 5000)(2750 100);
WIRE 16 273 (2750 5000)(-4250 5000);
WIRE 16 273 (2750 100)(-600 100);
WIRE 16 273 (-600 100)(-600 1750);
WIRE 16 273 (-600 -1050)(-600 100);
WIRE 16 273 (-4250 5000)(-4250 1750);
WIRE 16 273 (-600 1750)(-4250 1750);
WIRE 16 273 (-4250 1750)(-6350 1750);
WIRE 16 273 (-6350 -1050)(-600 -1050);
WIRE 16 273 (-6350 1750)(-6350 -1050);
WIRE 16 273 (-12350 -1050)(-6350 -1050);
WIRE 16 273 (-6350 1750)(-12350 1750);
WIRE 16 273 (-12350 1750)(-12350 -1050);
WIRE 16 -1 (-10850 3550)(-8150 3550);
FORCEPROP 2 LAST SIG_NAME R_MAC_10MHZ_RF_OUT
J 0
(-10110 3560);
DISPLAY 1.021277 (-10110 3560);
WIRE 16 -1 (-7900 2800)(-6050 2800);
FORCEPROP 2 LAST SIG_NAME UART_MAC_RX_FPGA_TX
J 0
(-7010 2810);
DISPLAY 1.021277 (-7010 2810);
WIRE 16 -1 (-7500 3050)(-7500 2400);
WIRE 16 -1 (-7500 3050)(-6050 3050);
FORCEPROP 2 LAST SIG_NAME UART_MAC_TX_FPGA_RX
J 0
(-7010 3060);
DISPLAY 1.021277 (-7010 3060);
WIRE 16 -1 (-7900 3050)(-7500 3050);
WIRE 16 -1 (-7500 2400)(-8950 2400);
WIRE 16 -1 (-7900 3300)(-6050 3300);
FORCEPROP 2 LAST SIG_NAME FPGA_IN_MAC_BITE OUT
J 0
(-7010 3310);
DISPLAY 1.021277 (-7010 3310);
WIRE 16 -1 (-7900 3550)(-6050 3550);
FORCEPROP 2 LAST SIG_NAME FPGA_IN_MAC_10MHZ_OUT
J 0
(-7060 3560);
DISPLAY 1.021277 (-7060 3560);
WIRE 16 -1 (-8450 2800)(-8450 2500);
WIRE 16 -1 (-8150 2800)(-8450 2800);
WIRE 16 -1 (-10300 2800)(-8450 2800);
FORCEPROP 2 LAST SIG_NAME R_MAC_UART_RX_FPGA_TX
J 0
(-10110 2810);
DISPLAY 1.021277 (-10110 2810);
WIRE 16 -1 (-8450 2500)(-8950 2500);
WIRE 16 -1 (-10850 2800)(-10300 2800);
WIRE 16 -1 (-10300 2800)(-10300 2200);
WIRE 16 -1 (-10300 2200)(-9200 2200);
WIRE 16 -1 (-10850 3300)(-9400 3300);
FORCEPROP 2 LAST SIG_NAME R_MAC_BITE OUT
J 0
(-10110 3310);
DISPLAY 1.021277 (-10110 3310);
WIRE 16 -1 (-9400 3300)(-8150 3300);
WIRE 16 -1 (-9400 3300)(-9400 3200);
WIRE 16 -1 (-9300 3200)(-9400 3200);
WIRE 16 -1 (-10350 3050)(-8150 3050);
FORCEPROP 2 LAST SIG_NAME R_MAC_UART_TX_FPGA_RX
J 0
(-10110 3060);
DISPLAY 1.021277 (-10110 3060);
WIRE 16 -1 (-10350 3050)(-10350 2100);
WIRE 16 -1 (-10850 3050)(-10350 3050);
WIRE 16 -1 (-10350 2100)(-9200 2100);
WIRE 16 -1 (-8950 2100)(-7100 2100);
FORCEPROP 2 LAST SIG_NAME DBG_UART_MAC_TX
J 0
(-8060 2110);
DISPLAY 1.021277 (-8060 2110);
WIRE 16 -1 (-9450 600)(-10800 600);
FORCEPROP 2 LAST SIG_NAME CONN_MICRO_USB_DM
J 0
(-10310 610);
DISPLAY 1.021277 (-10310 610);
WIRE 16 -1 (-10800 600)(-11100 600);
WIRE 16 -1 (-10800 600)(-10800 400);
WIRE 16 -1 (-3600 250)(-3600 100);
WIRE 16 -1 (-3400 250)(-3600 250);
WIRE 16 -1 (-3600 250)(-5700 250);
FORCEPROP 2 LAST SIG_NAME XP5R0V_USB_CONN_DET
J 0
(-5660 260);
DISPLAY 1.021277 (-5660 260);
WIRE 16 -1 (-3600 100)(-4000 100);
WIRE 16 -1 (-6950 6650)(-5250 6650);
FORCEPROP 2 LAST SIG_NAME R_MAC_PPS_OUTP
J 0
(-6360 6660);
DISPLAY 1.021277 (-6360 6660);
WIRE 16 -1 (-6950 6550)(-5250 6550);
FORCEPROP 2 LAST SIG_NAME R_MAC_PPS_OUTN
J 0
(-6360 6560);
DISPLAY 1.021277 (-6360 6560);
WIRE 16 -1 (1500 4150)(1850 4150);
WIRE 16 -1 (1850 4150)(1850 3800);
WIRE 16 -1 (1850 3800)(1850 2650);
WIRE 16 -1 (1450 3800)(1850 3800);
WIRE 16 -1 (1850 2650)(600 2650);
FORCEPROP 2 LAST SIG_NAME FPGA_IN_MAC_USB_OC_N
J 0
(640 2660);
DISPLAY 1.021277 (640 2660);
WIRE 16 -1 (-5700 450)(-3600 450);
FORCEPROP 2 LAST SIG_NAME MUX_USB_DM
J 0
(-5660 460);
DISPLAY 1.021277 (-5660 460);
WIRE 16 -1 (-3600 1200)(-3600 450);
WIRE 16 -1 (-3600 450)(-3400 450);
WIRE 16 -1 (-3100 1200)(-3600 1200);
WIRE 16 -1 (-5700 550)(-3550 550);
FORCEPROP 2 LAST SIG_NAME MUX_USB_DP
J 0
(-5660 560);
DISPLAY 1.021277 (-5660 560);
WIRE 16 -1 (-3550 1100)(-3550 550);
WIRE 16 -1 (-3550 550)(-3400 550);
WIRE 16 -1 (-3100 1100)(-3550 1100);
WIRE 16 -1 (-8950 2200)(-7100 2200);
FORCEPROP 2 LAST SIG_NAME DBG_UART_MAC_RX
J 0
(-8060 2210);
DISPLAY 1.021277 (-8060 2210);
WIRE 16 -1 (-6950 7450)(-6500 7450);
WIRE 16 -1 (-6500 7450)(-5250 7450);
FORCEPROP 2 LAST SIG_NAME R_MAC_PPS_IN1P
J 0
(-6360 7460);
DISPLAY 1.021277 (-6360 7460);
WIRE 16 -1 (-6500 7550)(-6500 7450);
WIRE 16 -1 (-6150 7550)(-6500 7550);
WIRE 16 -1 (-4550 6550)(-3550 6550);
FORCEPROP 2 LAST SIG_NAME MAC_ALARM
J 0
(-4060 6560);
DISPLAY 1.021277 (-4060 6560);
WIRE 16 -1 (-3550 6550)(-3050 6550);
WIRE 16 -1 (-3550 6550)(-3550 6450);
WIRE 16 -1 (-3450 6450)(-3550 6450);
WIRE 16 -1 (-8850 7250)(-7200 7250);
FORCEPROP 2 LAST SIG_NAME FPGA_OUT_MAC_PPS_IN0P
J 0
(-8810 7260);
DISPLAY 1.021277 (-8810 7260);
WIRE 16 -1 (-8850 6650)(-7200 6650);
FORCEPROP 2 LAST SIG_NAME FPGA_IN_MAC_PPS_OUTP
J 0
(-8810 6660);
DISPLAY 1.021277 (-8810 6660);
WIRE 16 -1 (-8850 6550)(-7200 6550);
FORCEPROP 2 LAST SIG_NAME FPGA_IN_MAC_PPS_OUTN
J 0
(-8810 6560);
DISPLAY 1.021277 (-8810 6560);
WIRE 16 -1 (-5250 7150)(-6500 7150);
FORCEPROP 2 LAST SIG_NAME R_MAC_PPS_IN0N
J 0
(-6360 7160);
DISPLAY 1.021277 (-6360 7160);
WIRE 16 -1 (-6500 7150)(-6500 7050);
WIRE 16 -1 (-6500 7150)(-6950 7150);
WIRE 16 -1 (-6150 7050)(-6500 7050);
WIRE 16 -1 (-850 6550)(-2350 6550);
FORCEPROP 2 LAST SIG_NAME FPGA_IN_MAC_ALARM_OUT_N
J 0
(-2060 6560);
DISPLAY 1.021277 (-2060 6560);
WIRE 16 -1 (-2350 6700)(-2350 6550);
WIRE 16 -1 (-2800 6550)(-2350 6550);
WIRE 16 -1 (-2050 6700)(-2350 6700);
WIRE 16 -1 (-7900 3800)(-5700 3800);
FORCEPROP 2 LAST SIG_NAME SMA_ANALOG_TUNING_IN
J 0
(-7060 3810);
DISPLAY 1.021277 (-7060 3810);
WIRE 16 -1 (-5700 100)(-4250 100);
FORCEPROP 2 LAST SIG_NAME RSVD_DBG_USB_MUX_SEL
J 0
(-5660 110);
DISPLAY 1.021277 (-5660 110);
WIRE 16 -1 (-6950 7250)(-5450 7250);
FORCEPROP 2 LAST SIG_NAME R_MAC_PPS_IN0P
J 0
(-6360 7260);
DISPLAY 1.021277 (-6360 7260);
WIRE 16 -1 (-5450 7250)(-5250 7250);
WIRE 16 -1 (-5450 7250)(-5450 7050);
WIRE 16 -1 (-5900 7050)(-5450 7050);
WIRE 16 -1 (-8850 7450)(-7200 7450);
FORCEPROP 2 LAST SIG_NAME FPGA_OUT_MAC_PPS_IN1P
J 0
(-8810 7460);
DISPLAY 1.021277 (-8810 7460);
WIRE 16 -1 (-3550 3900)(-2350 3900);
FORCEPROP 2 LAST SIG_NAME FPGA_OUT_MACUSBPOWER_EN
J 0
(-3510 3910);
DISPLAY 1.021277 (-3510 3910);
WIRE 16 -1 (-2300 3900)(-2350 3900);
WIRE 16 -1 (-2350 3500)(-2350 3900);
WIRE 16 -1 (-2300 4150)(-2300 3900);
WIRE 16 -1 (-2200 3900)(-2300 3900);
WIRE 16 -1 (-2050 4150)(-2300 4150);
WIRE 16 -1 (-1150 550)(-2500 550);
FORCEPROP 2 LAST SIG_NAME CONN_MICRO_USB_DP
J 0
(-2010 560);
DISPLAY 1.021277 (-2010 560);
WIRE 16 -1 (-3500 150)(-3400 150);
WIRE 16 -1 (-3500 0)(-3500 150);
WIRE 16 -1 (-3550 3800)(-2200 3800);
FORCEPROP 2 LAST SIG_NAME XP5R0V_USB_CONN_DET
J 0
(-3510 3810);
DISPLAY 1.021277 (-3510 3810);
WIRE 16 -1 (-1800 4150)(-1450 4150);
WIRE 16 -1 (-1450 4150)(-1450 3800);
WIRE 16 -1 (-1450 3800)(-750 3800);
FORCEPROP 2 LAST SIG_NAME USB_PWR_EN
J 0
(-1310 3810);
DISPLAY 1.021277 (-1310 3810);
WIRE 16 -1 (-1600 3800)(-1450 3800);
WIRE 16 -1 (-600 3800)(-750 3800);
WIRE 16 -1 (-750 3900)(-750 3800);
WIRE 16 -1 (-750 3900)(-650 3900);
WIRE 16 -1 (125 3800)(-600 3800);
WIRE 16 -1 (-600 3800)(-600 3500);
WIRE 16 -1 (-2500 850)(-2350 850);
WIRE 16 -1 (-2350 850)(-1150 850);
FORCEPROP 2 LAST SIG_NAME MAC_USB_DP
J 0
(-1660 860);
DISPLAY 1.021277 (-1660 860);
WIRE 16 -1 (-2350 1100)(-2350 850);
WIRE 16 -1 (-2850 1100)(-2350 1100);
WIRE 16 -1 (-2850 1200)(-2300 1200);
WIRE 16 -1 (-2300 1200)(-2300 750);
WIRE 16 -1 (-2300 750)(-1150 750);
FORCEPROP 2 LAST SIG_NAME MAC_USB_DM
J 0
(-1660 760);
DISPLAY 1.021277 (-1660 760);
WIRE 16 -1 (-2500 750)(-2300 750);
WIRE 16 -1 (-9450 500)(-10400 500);
FORCEPROP 2 LAST SIG_NAME CONN_MICRO_USB_DP
J 0
(-10310 510);
DISPLAY 1.021277 (-10310 510);
WIRE 16 -1 (-10400 400)(-10400 500);
WIRE 16 -1 (-10400 500)(-11100 500);
WIRE 16 -1 (-8050 350)(-8050 250);
WIRE 16 -1 (-8050 250)(-6950 250);
FORCEPROP 2 LAST SIG_NAME XP5R0V_USB_CONN_DET
J 0
(-7860 260);
DISPLAY 1.021277 (-7860 260);
WIRE 16 -1 (-8050 150)(-8050 250);
WIRE 16 -1 (900 1850)(1000 1850);
WIRE 16 -1 (1500 1850)(1000 1850);
WIRE 16 -1 (1000 1750)(1000 1850);
WIRE 16 -1 (1800 700)(700 700);
FORCEPROP 2 LAST SIG_NAME USB_PWR_EN
J 0
(1190 710);
DISPLAY 1.021277 (1190 710);
WIRE 16 -1 (700 1200)(700 1100);
WIRE 16 -1 (100 1100)(700 1100);
WIRE 16 -1 (100 1250)(100 1100);
WIRE 16 -1 (100 1000)(100 1100);
WIRE 16 -1 (100 1000)(200 1000);
WIRE 16 -1 (-1150 450)(-2500 450);
FORCEPROP 2 LAST SIG_NAME CONN_MICRO_USB_DM
J 0
(-2010 460);
DISPLAY 1.021277 (-2010 460);
WIRE 16 -1 (-6950 7350)(-5450 7350);
FORCEPROP 2 LAST SIG_NAME R_MAC_PPS_IN1N
J 0
(-6360 7360);
DISPLAY 1.021277 (-6360 7360);
WIRE 16 -1 (-5250 7350)(-5450 7350);
WIRE 16 -1 (-5450 7550)(-5450 7350);
WIRE 16 -1 (-5900 7550)(-5450 7550);
WIRE 16 -1 (-2800 7350)(-4550 7350);
FORCEPROP 2 LAST SIG_NAME R_MAC_USB_DM
J 0
(-4010 7360);
DISPLAY 1.021277 (-4010 7360);
WIRE 16 -1 (-8050 -200)(-8050 -100);
WIRE 16 -1 (1200 3800)(825 3800);
WIRE 16 -1 (-8850 7150)(-7200 7150);
FORCEPROP 2 LAST SIG_NAME FPGA_OUT_MAC_PPS_IN0N
J 0
(-8810 7160);
DISPLAY 1.021277 (-8810 7160);
WIRE 16 -1 (-8850 7350)(-7200 7350);
FORCEPROP 2 LAST SIG_NAME FPGA_OUT_MAC_PPS_IN1N
J 0
(-8810 7360);
DISPLAY 1.021277 (-8810 7360);
WIRE 16 -1 (-2550 7350)(-850 7350);
FORCEPROP 2 LAST SIG_NAME MUX_USB_DM
J 0
(-1460 7360);
DISPLAY 1.021277 (-1460 7360);
WIRE 16 -1 (-2800 7450)(-4550 7450);
FORCEPROP 2 LAST SIG_NAME R_MAC_USB_DP
J 0
(-4010 7460);
DISPLAY 1.021277 (-4010 7460);
WIRE 16 -1 (-2550 7450)(-850 7450);
FORCEPROP 2 LAST SIG_NAME MUX_USB_DP
J 0
(-1460 7460);
DISPLAY 1.021277 (-1460 7460);
DOT 1 (-750 3800);
DOT 1 (-1450 3800);
DOT 1 (-1100 3350);
DOT 1 (-9600 2400);
DOT 1 (-10350 3050);
DOT 1 (-10300 2800);
DOT 1 (-10600 4150);
DOT 1 (-11850 100);
DOT 1 (-11000 -550);
DOT 1 (-10600 -550);
DOT 1 (-8900 -550);
DOT 1 (-8500 -550);
DOT 1 (-11850 400);
DOT 1 (-11850 300);
DOT 1 (-11850 200);
DOT 1 (-11850 600);
DOT 1 (-10800 600);
DOT 1 (-10400 500);
DOT 1 (-10600 700);
DOT 1 (-8900 700);
DOT 1 (-8500 700);
DOT 1 (-8050 250);
DOT 1 (-8050 700);
DOT 1 (-600 3800);
DOT 1 (-600 100);
DOT 1 (-2350 850);
DOT 1 (-2300 750);
DOT 1 (-3550 550);
DOT 1 (-3600 450);
DOT 1 (-4000 950);
DOT 1 (-6350 -1050);
DOT 1 (-6350 1750);
DOT 1 (-9250 4750);
DOT 1 (-5050 3700);
DOT 1 (-7550 4750);
DOT 1 (-8800 4300);
DOT 1 (-9750 4750);
DOT 1 (-10200 4750);
DOT 1 (-10200 4300);
DOT 1 (-10400 4750);
DOT 1 (-9250 4300);
DOT 1 (-8350 4750);
DOT 1 (-8350 4300);
DOT 1 (-2350 6550);
DOT 1 (-3700 7250);
DOT 1 (-3700 6850);
DOT 1 (-4300 7250);
DOT 1 (-4200 7250);
DOT 1 (-5450 7350);
DOT 1 (-5450 7250);
DOT 1 (-5350 6750);
DOT 1 (-6500 7450);
DOT 1 (-6500 7150);
DOT 1 (-8800 4750);
DOT 1 (-600 2925);
DOT 1 (-200 2925);
DOT 1 (-200 4000);
DOT 1 (450 2925);
DOT 1 (1850 3800);
DOT 1 (2250 4000);
DOT 1 (100 1100);
DOT 1 (-4200 6850);
DOT 1 (-9750 4300);
DOT 1 (-8450 2800);
DOT 1 (-1100 2550);
DOT 1 (-4250 1750);
DOT 1 (600 1850);
DOT 1 (1000 1850);
DOT 1 (-2300 3900);
DOT 1 (-2350 3900);
DOT 1 (-3600 250);
DOT 1 (100 1850);
DOT 1 (-9400 3300);
DOT 1 (-3550 6550);
DOT 1 (-7500 3050);
FORCENOTE
ANALOG TUNING INPUT LEVEL: 0V TO 5V. RSVD FOR THE FUTURE USE.
(-8850 3950) 0;
DISPLAY LEFT (-8850 3950);
DISPLAY 1.021277 (-8850 3950);
FORCENOTE
MINIATURE_ATOMIC_CLOCK_MODULE
(-7550 9000) 0;
DISPLAY LEFT (-7550 9000);
DISPLAY 3.936170 (-7550 9000);
FORCENOTE
MICRO USB CONN
(-12150 -500) 0;
DISPLAY LEFT (-12150 -500);
DISPLAY 1.574468 (-12150 -500);
FORCENOTE
CURRENT LIMIT TPS2051
(-1700 4600) 0;
DISPLAY LEFT (-1700 4600);
DISPLAY 1.978723 (-1700 4600);
FORCENOTE
0.5A
(-600 4250) 0;
DISPLAY LEFT (-600 4250);
DISPLAY 1.021277 (-600 4250);
FORCENOTE
RESERVED FOR DEBUG.
(-6150 -600) 0;
DISPLAY LEFT (-6150 -600);
DISPLAY 1.574468 (-6150 -600);
FORCENOTE
SEL0: HIGH= CH2 ,MAC_USB<>MICRO_USB_CONN
(-6150 -200) 0;
DISPLAY LEFT (-6150 -200);
FORCENOTE
MP PHASE: DNP U10 AND POP R100.
(-3900 2000) 0;
DISPLAY LEFT (-3900 2000);
DISPLAY 1.255319 (-3900 2000);
FORCENOTE
SEL0: LOW = CH1 ,MAC_USB<>FPGA
(-6150 -300) 0;
DISPLAY LEFT (-6150 -300);
FORCENOTE
MP PHASE: DNP ALL AND POP ONLY R105,R106.
(-6150 -750) 0;
DISPLAY LEFT (-6150 -750);
DISPLAY 1.255319 (-6150 -750);
FORCENOTE
MP PHASE: DNP ALL.
(-10600 950) 0;
DISPLAY LEFT (-10600 950);
DISPLAY 1.574468 (-10600 950);
FORCENOTE
RESERVED FOR DEBUG
(-10600 1100) 0;
DISPLAY LEFT (-10600 1100);
DISPLAY 2.468085 (-10600 1100);
QUIT
